G04 ================== begin FILE IDENTIFICATION RECORD ==================*
G04 Layout Name:  9051_F0T_Panel_BD_Front_D_v02_20221209_1310.brd*
G04 Film Name:    panel*
G04 File Format:  Gerber RS274X*
G04 File Origin:  Cadence Allegro 17.2-S081*
G04 Origin Date:  Mon Dec 12 15:51:17 2022*
G04 *
G04 Layer:  DRAWING FORMAT/TITLE_BLOCK_A*
G04 Layer:  MANUFACTURING/PHOTOPLOT_OUTLINE*
G04 Layer:  DRAWING FORMAT/TITLE_BLOCK*
G04 Layer:  DRAWING FORMAT/TITLE_DATA_PANEL*
G04 Layer:  BOARD GEOMETRY/ASSEMBLY_NOTES*
G04 *
G04 Offset:    (0.00 0.00)*
G04 Mirror:    No*
G04 Mode:      Positive*
G04 Rotation:  0*
G04 FullContactRelief:  No*
G04 UndefLineWidth:     6.00*
G04 ================== end FILE IDENTIFICATION RECORD ====================*
%FSLAX25Y25*MOIN*%
%IR0*IPPOS*OFA0.00000B0.00000*MIA0B0*SFA1.00000B1.00000*%
%ADD10C,.006*%
G75*
%LPD*%
G75*
G36*
G01X-56221Y638976D02*
G02I-1968J0D01*
G37*
G36*
G01X374409Y66929D02*
G02I-1969J0D01*
G37*
G36*
G01X640935Y134013D02*
G02I-1969J0D01*
G37*
G54D10*
G01X-76641Y682577D02*
X-184897Y686057D01*
G01X-87717Y0D02*
X-173189D01*
G01X-173608Y698501D02*
X-173367Y705997D01*
X-171035Y705922D01*
X-170301Y705523D01*
X-169850Y705009D01*
X-169696Y704003D01*
X-169915Y703010D01*
X-170495Y702403D01*
X-171160Y702049D01*
X-173492Y702124D01*
G01X-171160Y702049D02*
X-169877Y698381D01*
G01X-165818Y704504D02*
X-165234Y705235D01*
X-164569Y705589D01*
X-163819Y705690D01*
X-162894Y705410D01*
X-162261Y704765D01*
X-162099Y704009D01*
X-162216Y703262D01*
X-162609Y702650D01*
X-164515Y701460D01*
X-165383Y700613D01*
X-165983Y699381D01*
X-166205Y698263D01*
X-162287Y698137D01*
G01X-159549Y698049D02*
X-159388Y703046D01*
G01X-159433Y701672D02*
X-159133Y702288D01*
X-158650Y702772D01*
X-157989Y703001D01*
X-157344Y702730D01*
X-156894Y702216D01*
X-156634Y701582D01*
X-156751Y697959D01*
G01X-156634Y701582D02*
X-156334Y702198D01*
X-155852Y702683D01*
X-155191Y702911D01*
X-154546Y702641D01*
X-154095Y702126D01*
X-153839Y701367D01*
X-153952Y697869D01*
G01X-152053Y697808D02*
X-151892Y702805D01*
G01X-151937Y701431D02*
X-151637Y702047D01*
X-151154Y702531D01*
X-150493Y702760D01*
X-149848Y702489D01*
X-149398Y701975D01*
X-149138Y701341D01*
X-149255Y697718D01*
G01X-149138Y701341D02*
X-148838Y701957D01*
X-148356Y702442D01*
X-147695Y702670D01*
X-147050Y702400D01*
X-146599Y701885D01*
X-146343Y701126D01*
X-146456Y697628D01*
G01X-117168Y-317735D02*
Y-322735D01*
G01X-118625Y-317735D02*
X-115711D01*
G01X-110801Y-322735D02*
X-113335D01*
Y-317735D01*
X-110801D01*
G01X-111815Y-320152D02*
X-113335D01*
G01X-108235Y-317735D02*
Y-322735D01*
X-105701D01*
G01X-101868Y-322902D02*
X-101995Y-322818D01*
Y-322652D01*
X-101868Y-322568D01*
X-101741Y-322652D01*
Y-322818D01*
X-101868Y-322902D01*
G01Y-320652D02*
X-101995Y-320568D01*
Y-320402D01*
X-101868Y-320318D01*
X-101741Y-320402D01*
Y-320568D01*
X-101868Y-320652D01*
G01X-97085Y-324402D02*
X-97718Y-323568D01*
X-98035Y-322735D01*
Y-319402D01*
X-97718Y-318568D01*
X-97085Y-317735D01*
G01X-91668D02*
X-92175Y-317902D01*
X-92555Y-318318D01*
X-92808Y-318818D01*
X-92998Y-319485D01*
X-93061Y-320235D01*
X-92998Y-320985D01*
X-92808Y-321652D01*
X-92555Y-322152D01*
X-92175Y-322568D01*
X-91668Y-322735D01*
X-91161Y-322568D01*
X-90781Y-322152D01*
X-90528Y-321652D01*
X-90338Y-320985D01*
X-90275Y-320235D01*
X-90338Y-319485D01*
X-90528Y-318818D01*
X-90781Y-318318D01*
X-91161Y-317902D01*
X-91668Y-317735D01*
G01X-87961Y-321735D02*
X-87581Y-322318D01*
X-87075Y-322652D01*
X-86505Y-322735D01*
X-85998Y-322652D01*
X-85491Y-322235D01*
X-85175Y-321735D01*
X-85111Y-321235D01*
X-85238Y-320652D01*
X-85681Y-320235D01*
X-86125Y-320068D01*
X-86695D01*
G01X-86125D02*
X-85745Y-319818D01*
X-85428Y-319402D01*
X-85301Y-318902D01*
X-85428Y-318402D01*
X-85745Y-317985D01*
X-86315Y-317735D01*
X-86885Y-317818D01*
X-87455Y-318152D01*
G01X-81151Y-324402D02*
X-80518Y-323568D01*
X-80201Y-322735D01*
Y-319402D01*
X-80518Y-318568D01*
X-81151Y-317735D01*
G01X-77761Y-321735D02*
X-77381Y-322318D01*
X-76875Y-322652D01*
X-76305Y-322735D01*
X-75798Y-322652D01*
X-75291Y-322235D01*
X-74975Y-321735D01*
X-74911Y-321235D01*
X-75038Y-320652D01*
X-75481Y-320235D01*
X-75925Y-320068D01*
X-76495D01*
G01X-75925D02*
X-75545Y-319818D01*
X-75228Y-319402D01*
X-75101Y-318902D01*
X-75228Y-318402D01*
X-75545Y-317985D01*
X-76115Y-317735D01*
X-76685Y-317818D01*
X-77255Y-318152D01*
G01X-72471Y-318568D02*
X-72091Y-318068D01*
X-71648Y-317818D01*
X-71141Y-317735D01*
X-70508Y-317902D01*
X-70065Y-318318D01*
X-69938Y-318818D01*
X-70001Y-319318D01*
X-70255Y-319735D01*
X-71521Y-320568D01*
X-72091Y-321152D01*
X-72471Y-321985D01*
X-72598Y-322735D01*
X-69938D01*
G01X-66295D02*
X-66168Y-321652D01*
X-65978Y-320735D01*
X-65725Y-319902D01*
X-65408Y-318985D01*
X-64901Y-317735D01*
X-67435D01*
G01X-61891Y-321068D02*
X-60245D01*
G01X-57171Y-318568D02*
X-56791Y-318068D01*
X-56348Y-317818D01*
X-55841Y-317735D01*
X-55208Y-317902D01*
X-54765Y-318318D01*
X-54638Y-318818D01*
X-54701Y-319318D01*
X-54955Y-319735D01*
X-56221Y-320568D01*
X-56791Y-321152D01*
X-57171Y-321985D01*
X-57298Y-322735D01*
X-54638D01*
G01X-52261Y-321735D02*
X-51881Y-322318D01*
X-51375Y-322652D01*
X-50805Y-322735D01*
X-50298Y-322652D01*
X-49791Y-322235D01*
X-49475Y-321735D01*
X-49411Y-321235D01*
X-49538Y-320652D01*
X-49981Y-320235D01*
X-50425Y-320068D01*
X-50995D01*
G01X-50425D02*
X-50045Y-319818D01*
X-49728Y-319402D01*
X-49601Y-318902D01*
X-49728Y-318402D01*
X-50045Y-317985D01*
X-50615Y-317735D01*
X-51185Y-317818D01*
X-51755Y-318152D01*
G01X-45008Y-322735D02*
Y-317735D01*
X-47351Y-321318D01*
X-44185D01*
G01X-42061Y-321985D02*
X-41681Y-322402D01*
X-41238Y-322652D01*
X-40668Y-322735D01*
X-40098Y-322568D01*
X-39655Y-322235D01*
X-39338Y-321652D01*
X-39275Y-320985D01*
X-39401Y-320318D01*
X-39718Y-319902D01*
X-40161Y-319568D01*
X-40605Y-319485D01*
X-41048Y-319568D01*
X-41618Y-319902D01*
X-41428Y-317735D01*
X-39718D01*
G01X-31671Y-322735D02*
Y-317735D01*
X-29265D01*
G01X-30151Y-320152D02*
X-31671D01*
G01X-26951Y-322735D02*
X-25368Y-317735D01*
X-23785Y-322735D01*
G01X-24355Y-320985D02*
X-26381D01*
G01X-21598Y-322735D02*
X-18938Y-317735D01*
G01X-21598D02*
X-18938Y-322735D01*
G01X-15168Y-322902D02*
X-15295Y-322818D01*
Y-322652D01*
X-15168Y-322568D01*
X-15041Y-322652D01*
Y-322818D01*
X-15168Y-322902D01*
G01Y-320652D02*
X-15295Y-320568D01*
Y-320402D01*
X-15168Y-320318D01*
X-15041Y-320402D01*
Y-320568D01*
X-15168Y-320652D01*
G01X-10385Y-324402D02*
X-11018Y-323568D01*
X-11335Y-322735D01*
Y-319402D01*
X-11018Y-318568D01*
X-10385Y-317735D01*
G01X-4968D02*
X-5475Y-317902D01*
X-5855Y-318318D01*
X-6108Y-318818D01*
X-6298Y-319485D01*
X-6361Y-320235D01*
X-6298Y-320985D01*
X-6108Y-321652D01*
X-5855Y-322152D01*
X-5475Y-322568D01*
X-4968Y-322735D01*
X-4461Y-322568D01*
X-4081Y-322152D01*
X-3828Y-321652D01*
X-3638Y-320985D01*
X-3575Y-320235D01*
X-3638Y-319485D01*
X-3828Y-318818D01*
X-4081Y-318318D01*
X-4461Y-317902D01*
X-4968Y-317735D01*
G01X-1261Y-321735D02*
X-881Y-322318D01*
X-375Y-322652D01*
X195Y-322735D01*
X702Y-322652D01*
X1209Y-322235D01*
X1525Y-321735D01*
X1589Y-321235D01*
X1462Y-320652D01*
X1019Y-320235D01*
X575Y-320068D01*
X5D01*
G01X575D02*
X955Y-319818D01*
X1272Y-319402D01*
X1399Y-318902D01*
X1272Y-318402D01*
X955Y-317985D01*
X385Y-317735D01*
X-185Y-317818D01*
X-755Y-318152D01*
G01X5549Y-324402D02*
X6182Y-323568D01*
X6499Y-322735D01*
Y-319402D01*
X6182Y-318568D01*
X5549Y-317735D01*
G01X8939Y-321735D02*
X9319Y-322318D01*
X9825Y-322652D01*
X10395Y-322735D01*
X10902Y-322652D01*
X11409Y-322235D01*
X11725Y-321735D01*
X11789Y-321235D01*
X11662Y-320652D01*
X11219Y-320235D01*
X10775Y-320068D01*
X10205D01*
G01X10775D02*
X11155Y-319818D01*
X11472Y-319402D01*
X11599Y-318902D01*
X11472Y-318402D01*
X11155Y-317985D01*
X10585Y-317735D01*
X10015Y-317818D01*
X9445Y-318152D01*
G01X14355Y-322152D02*
X14799Y-322568D01*
X15305Y-322735D01*
X15812Y-322568D01*
X16255Y-322068D01*
X16572Y-321318D01*
X16699Y-320568D01*
Y-319652D01*
X16572Y-318902D01*
X16255Y-318235D01*
X15875Y-317902D01*
X15432Y-317735D01*
X14925Y-317902D01*
X14545Y-318235D01*
X14292Y-318735D01*
X14165Y-319402D01*
X14292Y-319985D01*
X14609Y-320568D01*
X14989Y-320902D01*
X15432Y-320985D01*
X15939Y-320818D01*
X16319Y-320402D01*
X16699Y-319652D01*
G01X20405Y-322735D02*
X20532Y-321652D01*
X20722Y-320735D01*
X20975Y-319902D01*
X21292Y-318985D01*
X21799Y-317735D01*
X19265D01*
G01X24809Y-321068D02*
X26455D01*
G01X29339Y-321735D02*
X29719Y-322318D01*
X30225Y-322652D01*
X30795Y-322735D01*
X31302Y-322652D01*
X31809Y-322235D01*
X32125Y-321735D01*
X32189Y-321235D01*
X32062Y-320652D01*
X31619Y-320235D01*
X31175Y-320068D01*
X30605D01*
G01X31175D02*
X31555Y-319818D01*
X31872Y-319402D01*
X31999Y-318902D01*
X31872Y-318402D01*
X31555Y-317985D01*
X30985Y-317735D01*
X30415Y-317818D01*
X29845Y-318152D01*
G01X34629Y-320652D02*
X35072Y-320068D01*
X35452Y-319735D01*
X35959Y-319568D01*
X36402Y-319735D01*
X36719Y-320068D01*
X36972Y-320568D01*
X37035Y-321152D01*
X36972Y-321652D01*
X36719Y-322152D01*
X36339Y-322568D01*
X35895Y-322735D01*
X35389Y-322568D01*
X34945Y-322068D01*
X34692Y-321318D01*
X34629Y-320485D01*
X34755Y-319402D01*
X34945Y-318818D01*
X35262Y-318235D01*
X35705Y-317818D01*
X36149Y-317735D01*
X36592Y-317902D01*
X36909Y-318318D01*
G01X40932Y-322735D02*
Y-317735D01*
X40172Y-318735D01*
G01Y-322735D02*
X41692D01*
G01X46792D02*
Y-317735D01*
X44449Y-321318D01*
X47615D01*
G01X-129168Y-252735D02*
Y-327735D01*
X370832D01*
Y-252735D01*
X-129168D01*
G01X-92460Y680624D02*
X-76641Y682577D01*
X-92302Y685543D01*
X-92460Y680624D01*
G01X-77874Y-9843D02*
Y-80079D01*
G01Y51000D02*
Y7874D01*
G03X-70000Y0I7874J0D01*
G01X-77874Y54252D02*
X-7874D01*
G01Y51000D02*
Y584252D01*
X-77874D01*
Y51000D01*
G01X-7874Y519252D02*
X-77874D01*
G01Y584252D02*
G02X-70000Y592126I7874J0D01*
G01X-15748D01*
G02X-7874Y584252I0J-7874D01*
G01X-77874Y625220D02*
Y607874D01*
G03X-70000Y600000I7874J0D01*
G01X-46104D01*
G01X-77874Y625220D02*
Y678346D01*
G02X-70000Y686220I7874J0D01*
G01X-77874Y696220D02*
Y736220D01*
G01X102801Y726220D02*
X-77874D01*
G01X-70874Y727720D02*
X-77874Y726220D01*
X-70874Y724720D01*
Y727720D01*
G01X-70000Y0D02*
X-46378D01*
G01X-53110Y598819D02*
G03I-1575J0D01*
G01X-62559Y592126D02*
G03Y600000I0J3937D01*
G01X-70000Y686220D02*
X-46378D01*
G01X-30630Y-2990D02*
Y-39390D01*
G01X-15748Y0D02*
X-46378D01*
G01X-46104Y600000D02*
X-15446D01*
G01X-29488Y598819D02*
G03I-1575J0D01*
G01X-37362D02*
G03I-1575J0D01*
G01X-45236D02*
G03I-1575J0D01*
G01X-46378Y686220D02*
X-15748D01*
G01Y0D02*
G03X-7874Y7874I0J7874D01*
G01D02*
Y51000D01*
G01X0Y29528D02*
G03X-7874I-3937J0D01*
G01X0Y49213D02*
G02X-7874I-3937J0D01*
G01X0Y29528D02*
G03X-7874I-3937J0D01*
G01X0Y49213D02*
G02X-7874I-3937J0D01*
G01Y149731D02*
G02X0I3937J0D01*
G01X-7874Y169417D02*
G03X0I3937J0D01*
G01X-7874Y237030D02*
G02X0I3937J0D01*
G01X-7874Y256716D02*
G03X0I3937J0D01*
G01Y429504D02*
G03X-7874I-3937J0D01*
G01X0Y449190D02*
G02X-7874I-3937J0D01*
G01X0Y516803D02*
G03X-7874I-3937J0D01*
G01X0Y536489D02*
G02X-7874I-3937J0D01*
G01Y625220D02*
Y607874D01*
G02X-15748Y600000I-7874J0D01*
G01X-23189Y592126D02*
G02Y600000I0J3937D01*
G01X-7874Y678346D02*
Y625220D01*
G01Y637007D02*
G02X0I3937J0D01*
G01X-7874D02*
G02X0I3937J0D01*
G01X-7874Y656692D02*
G03X0I3937J0D01*
G01X-7874D02*
G03X0I3937J0D01*
G01X-15748Y686220D02*
G02X-7874Y678346I0J-7874D01*
G01X7874Y0D02*
X146850D01*
G01X0Y7874D02*
G03X7874Y0I7874J0D01*
G01X0Y272417D02*
Y7874D01*
G01X2165Y277841D02*
G03X0Y272417I5710J-5423D01*
G01X4331Y283264D02*
G02X2165Y277841I-7874J1D01*
G01X4331Y307087D02*
Y283264D01*
G01X12205Y314961D02*
G03X4331Y307087I0J-7874D01*
G01X42716Y314961D02*
X12205D01*
G01X4330Y402956D02*
Y379133D01*
G01D02*
G03X12204Y371259I7874J0D01*
G01D02*
X25393D01*
G01X0Y413803D02*
G03X2165Y408379I7875J-1D01*
G01D02*
G02X4330Y402956I-5709J-5423D01*
G01X0Y678346D02*
Y413803D01*
G01X146850Y686220D02*
X7874D01*
G01D02*
G03X0Y678346I0J-7874D01*
G01X33267Y354921D02*
G03X41141Y347047I7874J0D01*
G01X25393Y371259D02*
G02X33267Y363385I0J-7874D01*
G01D02*
Y354921D01*
G01X110102Y221301D02*
X50284D01*
Y93484D01*
G01X50540Y170941D02*
X81982D01*
Y172219D01*
G01X50590Y322835D02*
G02X42716Y314961I-7874J0D01*
G01X50590Y331299D02*
Y322835D01*
G01X58464Y339173D02*
G03X50590Y331299I0J-7874D01*
G01X41141Y347047D02*
X96260D01*
G01X44622Y464919D02*
X104440D01*
Y592736D01*
G01X65832Y-252735D02*
Y-327735D01*
G01Y-302735D02*
X168832D01*
Y-277735D01*
G01X65832D02*
X168832D01*
G01X113583Y339173D02*
X58464D01*
G01X104184Y515279D02*
X72742D01*
Y514001D01*
G01X96260Y347047D02*
G03X104134Y354921I0J7874D01*
G01X121457Y322835D02*
Y331299D01*
G01X129331Y314961D02*
G02X121457Y322835I0J7874D01*
G01Y331299D02*
G03X113583Y339173I-7874J0D01*
G01X104134Y354921D02*
Y363385D01*
G01D02*
G02X112008Y371259I7874J0D01*
G01D02*
X142519D01*
G01X116826Y707470D02*
X112176D01*
Y719970D01*
X116826D01*
G01X142520Y314961D02*
X129331D01*
G01X142520D02*
G02X150394Y307087I0J-7874D01*
G01Y283264D01*
G03X152559Y277841I7874J0D01*
G01X142519Y371259D02*
G03X150393Y379133I0J7874D01*
G01X146850Y0D02*
G03X154724Y7874I0J7874D01*
G01X162598D02*
G03X170472Y0I7874J0D01*
G01X154724Y7874D02*
Y272417D01*
G01X162598D02*
Y7874D01*
G01X154724Y29528D02*
G02X162598I3937J0D01*
G01X154724Y49214D02*
G03X162598I3937J0D01*
G01X154724Y149731D02*
G02X162598I3937J0D01*
G01X154724Y169417D02*
G03X162598I3937J0D01*
G01X154724Y237030D02*
G02X162598I3937J0D01*
G01X154724Y256716D02*
G03X162598I3937J0D01*
G01X154724Y272417D02*
G03X152559Y277841I-7875J1D01*
G01X164763D02*
G03X162598Y272417I5710J-5423D01*
G01X150393Y379133D02*
Y402956D01*
G01D02*
G02X152559Y408379I7874J-1D01*
G01D02*
G03X154724Y413803I-5710J5423D01*
G01X162598D02*
G03X164763Y408379I7875J-1D01*
G01X154724Y413803D02*
Y678346D01*
G01X162598D02*
Y413803D01*
G01Y429504D02*
G03X154724I-3937J0D01*
G01X162598Y449190D02*
G02X154724I-3937J0D01*
G01X162598Y516803D02*
G03X154724I-3937J0D01*
G01X162598Y536489D02*
G02X154724I-3937J0D01*
G01X162598Y637006D02*
G03X154724I-3937J0D01*
G01X162598Y656692D02*
G02X154724I-3937J0D01*
G01Y678346D02*
G03X146850Y686220I-7874J0D01*
G01X170472D02*
G03X162598Y678346I0J-7874D01*
G01X176339Y-312735D02*
Y-307735D01*
X177605D01*
X178112Y-307985D01*
X178492Y-308318D01*
X178809Y-308818D01*
X179062Y-309402D01*
X179125Y-310235D01*
X179062Y-311068D01*
X178809Y-311652D01*
X178492Y-312152D01*
X178112Y-312485D01*
X177605Y-312735D01*
X176339D01*
G01X181249D02*
X182832Y-307735D01*
X184415Y-312735D01*
G01X183845Y-310985D02*
X181819D01*
G01X187932Y-307735D02*
Y-312735D01*
G01X186475Y-307735D02*
X189389D01*
G01X194299Y-312735D02*
X191765D01*
Y-307735D01*
X194299D01*
G01X193285Y-310152D02*
X191765D01*
G01X198132Y-312902D02*
X198005Y-312818D01*
Y-312652D01*
X198132Y-312568D01*
X198259Y-312652D01*
Y-312818D01*
X198132Y-312902D01*
G01Y-310652D02*
X198005Y-310568D01*
Y-310402D01*
X198132Y-310318D01*
X198259Y-310402D01*
Y-310568D01*
X198132Y-310652D01*
G01X170832Y-252735D02*
Y-327735D01*
G01X168832Y-252735D02*
Y-327735D01*
G01X170832Y-302735D02*
X370832D01*
G01X176465Y-287735D02*
Y-282735D01*
X177985D01*
X178492Y-282985D01*
X178872Y-283568D01*
X178999Y-284235D01*
X178872Y-284902D01*
X178555Y-285402D01*
X177985Y-285652D01*
X176465D01*
G01X181692Y-287902D02*
X183972Y-282735D01*
G01X186475Y-287735D02*
Y-282735D01*
X189389Y-287735D01*
Y-282735D01*
G01X193032Y-287902D02*
X192905Y-287818D01*
Y-287652D01*
X193032Y-287568D01*
X193159Y-287652D01*
Y-287818D01*
X193032Y-287902D01*
G01Y-285652D02*
X192905Y-285568D01*
Y-285402D01*
X193032Y-285318D01*
X193159Y-285402D01*
Y-285568D01*
X193032Y-285652D01*
G01X170832Y-277735D02*
X370832D01*
G01X176465Y-262735D02*
Y-257735D01*
X177985D01*
X178492Y-257985D01*
X178872Y-258568D01*
X178999Y-259235D01*
X178872Y-259902D01*
X178555Y-260402D01*
X177985Y-260652D01*
X176465D01*
G01X181565Y-262735D02*
Y-257735D01*
X183149D01*
X183655Y-257985D01*
X183972Y-258318D01*
X184099Y-258985D01*
X183972Y-259652D01*
X183592Y-260068D01*
X183149Y-260318D01*
X181565D01*
G01X183149D02*
X184099Y-262735D01*
G01X187932D02*
X187425Y-262652D01*
X186982Y-262318D01*
X186602Y-261818D01*
X186349Y-261235D01*
X186222Y-260568D01*
Y-259902D01*
X186349Y-259235D01*
X186602Y-258652D01*
X186982Y-258152D01*
X187425Y-257818D01*
X187932Y-257735D01*
X188439Y-257818D01*
X188882Y-258152D01*
X189262Y-258652D01*
X189515Y-259235D01*
X189642Y-259902D01*
Y-260568D01*
X189515Y-261235D01*
X189262Y-261818D01*
X188882Y-262318D01*
X188439Y-262652D01*
X187932Y-262735D01*
G01X191765Y-261735D02*
X192082Y-262235D01*
X192462Y-262568D01*
X192905Y-262735D01*
X193412Y-262568D01*
X193792Y-262235D01*
X194172Y-261735D01*
X194299Y-261068D01*
Y-257735D01*
G01X199399Y-262735D02*
X196865D01*
Y-257735D01*
X199399D01*
G01X198385Y-260152D02*
X196865D01*
G01X204625Y-258152D02*
X204245Y-257902D01*
X203802Y-257735D01*
X203295D01*
X202725Y-257985D01*
X202282Y-258402D01*
X201965Y-258902D01*
X201712Y-259735D01*
X201649Y-260485D01*
X201775Y-261235D01*
X201965Y-261735D01*
X202345Y-262235D01*
X202789Y-262568D01*
X203232Y-262735D01*
X203675D01*
X204119Y-262568D01*
X204499Y-262318D01*
X204815Y-261985D01*
G01X208332Y-257735D02*
Y-262735D01*
G01X206875Y-257735D02*
X209789D01*
G01X213432Y-262902D02*
X213305Y-262818D01*
Y-262652D01*
X213432Y-262568D01*
X213559Y-262652D01*
Y-262818D01*
X213432Y-262902D01*
G01Y-260652D02*
X213305Y-260568D01*
Y-260402D01*
X213432Y-260318D01*
X213559Y-260402D01*
Y-260568D01*
X213432Y-260652D01*
G01X170472Y0D02*
X309448D01*
G01X166929Y307087D02*
Y283264D01*
G01D02*
G02X164763Y277841I-7874J1D01*
G01X174803Y314961D02*
G03X166929Y307087I0J-7874D01*
G01X205314Y314961D02*
X174803D01*
G01X166928Y402956D02*
Y379133D01*
G01D02*
G03X174802Y371259I7874J0D01*
G01D02*
X187991D01*
G01X164763Y408379D02*
G02X166928Y402956I-5709J-5423D01*
G01X309448Y686220D02*
X170472D01*
G01X213188Y322835D02*
G02X205314Y314961I-7874J0D01*
G01X195865Y354921D02*
G03X203739Y347047I7874J0D01*
G01D02*
X258858D01*
G01X187991Y371259D02*
G02X195865Y363385I0J-7874D01*
G01D02*
Y354921D01*
G01X197426Y707470D02*
X202076D01*
Y719970D01*
X197426D01*
G01X272700Y221301D02*
X212882D01*
Y93484D01*
G01X213138Y170941D02*
X244580D01*
Y172219D01*
G01X213188Y331299D02*
Y322835D01*
G01X276181Y339173D02*
X221062D01*
G01D02*
G03X213188Y331299I0J-7874D01*
G01X207220Y464919D02*
X267038D01*
Y592736D01*
G01X211451Y726220D02*
X392125D01*
G01X266782Y515279D02*
X235340D01*
Y514001D01*
G01X258858Y347047D02*
G03X266732Y354921I0J7874D01*
G01D02*
Y363385D01*
G01D02*
G02X274606Y371259I7874J0D01*
G01X283832Y-302735D02*
Y-327735D01*
G01X288465Y-305235D02*
Y-310235D01*
X290999D01*
G01X294072Y-305235D02*
X295592D01*
G01X294832D02*
Y-310235D01*
G01X294072D02*
X295592D01*
G01X300439Y-307568D02*
X300692Y-307318D01*
X300882Y-306902D01*
X301009Y-306318D01*
X300882Y-305818D01*
X300629Y-305485D01*
X300185Y-305235D01*
X298475D01*
Y-310235D01*
X300565D01*
X301009Y-309902D01*
X301262Y-309402D01*
X301389Y-308818D01*
X301262Y-308235D01*
X300882Y-307735D01*
X300439Y-307568D01*
X298475D01*
G01X305032Y-310402D02*
X304905Y-310318D01*
Y-310152D01*
X305032Y-310068D01*
X305159Y-310152D01*
Y-310318D01*
X305032Y-310402D01*
G01Y-308152D02*
X304905Y-308068D01*
Y-307902D01*
X305032Y-307818D01*
X305159Y-307902D01*
Y-308068D01*
X305032Y-308152D01*
G01X291929Y314961D02*
G02X284055Y322835I0J7874D01*
G01D02*
Y331299D01*
G01X305118Y314961D02*
X291929D01*
G01X284055Y331299D02*
G03X276181Y339173I-7874J0D01*
G01X274606Y371259D02*
X305117D01*
G01X309448Y0D02*
G03X317322Y7874I0J7874D01*
G01X312992Y283264D02*
Y307087D01*
G01X315157Y277841D02*
G02X312992Y283264I5709J5423D01*
G01Y307087D02*
G03X305118Y314961I-7874J0D01*
G01X312991Y379133D02*
Y402956D01*
G01X305117Y371259D02*
G03X312991Y379133I0J7874D01*
G01Y402956D02*
G02X315157Y408379I7874J-1D01*
G01X317322Y678346D02*
G03X309448Y686220I-7874J0D01*
G01X328832Y-302735D02*
Y-327735D01*
G01X332732Y-305235D02*
Y-310235D01*
G01X331275Y-305235D02*
X334189D01*
G01X337832Y-310235D02*
X337452Y-310152D01*
X337072Y-309818D01*
X336819Y-309235D01*
X336692Y-308568D01*
X336819Y-307902D01*
X337072Y-307318D01*
X337452Y-306985D01*
X337832Y-306902D01*
X338212Y-306985D01*
X338592Y-307318D01*
X338845Y-307902D01*
X338909Y-308568D01*
X338845Y-309235D01*
X338592Y-309818D01*
X338212Y-310152D01*
X337832Y-310235D01*
G01X342932D02*
X342552Y-310152D01*
X342172Y-309818D01*
X341919Y-309235D01*
X341792Y-308568D01*
X341919Y-307902D01*
X342172Y-307318D01*
X342552Y-306985D01*
X342932Y-306902D01*
X343312Y-306985D01*
X343692Y-307318D01*
X343945Y-307902D01*
X344009Y-308568D01*
X343945Y-309235D01*
X343692Y-309818D01*
X343312Y-310152D01*
X342932Y-310235D01*
G01X348032D02*
Y-305235D01*
G01X353132Y-310402D02*
X353005Y-310318D01*
Y-310152D01*
X353132Y-310068D01*
X353259Y-310152D01*
Y-310318D01*
X353132Y-310402D01*
G01Y-308152D02*
X353005Y-308068D01*
Y-307902D01*
X353132Y-307818D01*
X353259Y-307902D01*
Y-308068D01*
X353132Y-308152D01*
G01X328832Y-277735D02*
Y-302735D01*
G01X331465Y-285235D02*
Y-280235D01*
X333049D01*
X333555Y-280485D01*
X333872Y-280818D01*
X333999Y-281485D01*
X333872Y-282152D01*
X333492Y-282568D01*
X333049Y-282818D01*
X331465D01*
G01X333049D02*
X333999Y-285235D01*
G01X339099D02*
X336565D01*
Y-280235D01*
X339099D01*
G01X338085Y-282652D02*
X336565D01*
G01X341349Y-280235D02*
X342932Y-285235D01*
X344515Y-280235D01*
G01X348032Y-285402D02*
X347905Y-285318D01*
Y-285152D01*
X348032Y-285068D01*
X348159Y-285152D01*
Y-285318D01*
X348032Y-285402D01*
G01Y-283152D02*
X347905Y-283068D01*
Y-282902D01*
X348032Y-282818D01*
X348159Y-282902D01*
Y-283068D01*
X348032Y-283152D01*
G01X360629Y0D02*
X333070D01*
G01D02*
G02X325196Y7874I0J7874D01*
G01X317322D02*
Y272417D01*
G01X325196Y7874D02*
Y79000D01*
G01X317322Y49213D02*
G03X325196I3937J0D01*
G01X317322Y29528D02*
G02X325196I3937J0D01*
G01X317322Y49213D02*
G03X325196I3937J0D01*
G01X317322Y29528D02*
G02X325196I3937J0D01*
G01Y79000D02*
Y637332D01*
G01X317322Y149731D02*
G02X325196I3937J0D01*
G01X317322Y169417D02*
G03X325196I3937J0D01*
G01X317322Y237030D02*
G02X325196I3937J0D01*
G01X317322Y256716D02*
G03X325196I3937J0D01*
G01X317322Y272417D02*
G03X315157Y277841I-7875J1D01*
G01Y408379D02*
G03X317322Y413803I-5710J5423D01*
G01D02*
Y678346D01*
G01X325196Y429504D02*
G03X317322I-3937J0D01*
G01X325196Y449190D02*
G02X317322I-3937J0D01*
G01X325196Y516803D02*
G03X317322I-3937J0D01*
G01X325196Y536489D02*
G02X317322I-3937J0D01*
G01X325196Y637007D02*
G03X317322I-3937J0D01*
G01X325196D02*
G03X317322I-3937J0D01*
G01X325196Y637220D02*
Y678346D01*
G01Y656692D02*
G02X317322I-3937J0D01*
G01X325196D02*
G02X317322I-3937J0D01*
G01X360629Y686220D02*
X333070D01*
G01X325196Y678346D02*
G02X333070Y686220I7874J0D01*
G01X351592Y-329435D02*
X351672Y-329360D01*
X351732Y-329235D01*
X351772Y-329060D01*
X351732Y-328910D01*
X351652Y-328810D01*
X351512Y-328735D01*
X350972D01*
Y-330235D01*
X351632D01*
X351772Y-330135D01*
X351852Y-329985D01*
X351892Y-329810D01*
X351852Y-329635D01*
X351732Y-329485D01*
X351592Y-329435D01*
X350972D01*
G01X352992Y-330235D02*
Y-329235D01*
G01Y-329410D02*
X352912Y-329310D01*
X352792Y-329260D01*
X352652Y-329235D01*
X352512Y-329285D01*
X352392Y-329385D01*
X352312Y-329535D01*
X352272Y-329735D01*
X352312Y-329935D01*
X352392Y-330085D01*
X352512Y-330185D01*
X352652Y-330235D01*
X352792Y-330210D01*
X352912Y-330135D01*
X352992Y-330035D01*
G01X353532Y-330060D02*
X353632Y-330160D01*
X353772Y-330235D01*
X353892D01*
X354012Y-330185D01*
X354092Y-330110D01*
X354132Y-330010D01*
X354112Y-329860D01*
X354032Y-329785D01*
X353672Y-329635D01*
X353592Y-329460D01*
X353632Y-329335D01*
X353712Y-329260D01*
X353832Y-329235D01*
X353952Y-329260D01*
X354072Y-329335D01*
G01X354732Y-329560D02*
X355372D01*
X355312Y-329385D01*
X355212Y-329285D01*
X355072Y-329235D01*
X354932Y-329260D01*
X354812Y-329335D01*
X354732Y-329510D01*
X354692Y-329660D01*
Y-329810D01*
X354732Y-329960D01*
X354832Y-330110D01*
X354952Y-330210D01*
X355092Y-330235D01*
X355232Y-330185D01*
X355372Y-330035D01*
G01X355872Y-330235D02*
Y-328735D01*
G01Y-329485D02*
X355972Y-329335D01*
X356092Y-329260D01*
X356212Y-329235D01*
X356392Y-329285D01*
X356512Y-329385D01*
X356592Y-329560D01*
Y-329760D01*
X356552Y-329960D01*
X356472Y-330110D01*
X356332Y-330210D01*
X356212Y-330235D01*
X356092Y-330210D01*
X355972Y-330135D01*
X355872Y-330010D01*
G01X357432Y-330235D02*
X357312Y-330210D01*
X357192Y-330110D01*
X357112Y-329935D01*
X357072Y-329735D01*
X357112Y-329535D01*
X357192Y-329360D01*
X357312Y-329260D01*
X357432Y-329235D01*
X357552Y-329260D01*
X357672Y-329360D01*
X357752Y-329535D01*
X357772Y-329735D01*
X357752Y-329935D01*
X357672Y-330110D01*
X357552Y-330210D01*
X357432Y-330235D01*
G01X358992D02*
Y-329235D01*
G01Y-329410D02*
X358912Y-329310D01*
X358792Y-329260D01*
X358652Y-329235D01*
X358512Y-329285D01*
X358392Y-329385D01*
X358312Y-329535D01*
X358272Y-329735D01*
X358312Y-329935D01*
X358392Y-330085D01*
X358512Y-330185D01*
X358652Y-330235D01*
X358792Y-330210D01*
X358912Y-330135D01*
X358992Y-330035D01*
G01X359552Y-330235D02*
Y-329235D01*
G01Y-329435D02*
X359652Y-329335D01*
X359752Y-329260D01*
X359892Y-329235D01*
X359992Y-329260D01*
X360112Y-329335D01*
G01X361392Y-328735D02*
Y-330235D01*
G01Y-330010D02*
X361312Y-330135D01*
X361192Y-330210D01*
X361052Y-330235D01*
X360892Y-330185D01*
X360772Y-330060D01*
X360692Y-329910D01*
X360672Y-329735D01*
X360692Y-329560D01*
X360772Y-329410D01*
X360892Y-329285D01*
X361052Y-329235D01*
X361192Y-329260D01*
X361292Y-329310D01*
X361392Y-329410D01*
G01X363032Y-330235D02*
Y-328735D01*
X363532D01*
X363692Y-328810D01*
X363792Y-328910D01*
X363832Y-329110D01*
X363792Y-329310D01*
X363672Y-329435D01*
X363532Y-329510D01*
X363032D01*
G01X363532D02*
X363832Y-330235D01*
G01X364332Y-329560D02*
X364972D01*
X364912Y-329385D01*
X364812Y-329285D01*
X364672Y-329235D01*
X364532Y-329260D01*
X364412Y-329335D01*
X364332Y-329510D01*
X364292Y-329660D01*
Y-329810D01*
X364332Y-329960D01*
X364432Y-330110D01*
X364552Y-330210D01*
X364692Y-330235D01*
X364832Y-330185D01*
X364972Y-330035D01*
G01X365472Y-329235D02*
X365832Y-330235D01*
X366192Y-329235D01*
G01X367032Y-330285D02*
X366992Y-330260D01*
Y-330210D01*
X367032Y-330185D01*
X367072Y-330210D01*
Y-330260D01*
X367032Y-330285D01*
G01X368192Y-330235D02*
X368232Y-329910D01*
X368292Y-329635D01*
X368372Y-329385D01*
X368472Y-329110D01*
X368632Y-328735D01*
X367832D01*
G01X369592Y-329435D02*
X369672Y-329360D01*
X369732Y-329235D01*
X369772Y-329060D01*
X369732Y-328910D01*
X369652Y-328810D01*
X369512Y-328735D01*
X368972D01*
Y-330235D01*
X369632D01*
X369772Y-330135D01*
X369852Y-329985D01*
X369892Y-329810D01*
X369852Y-329635D01*
X369732Y-329485D01*
X369592Y-329435D01*
X368972D01*
G01X384251Y0D02*
X360629D01*
G01Y686220D02*
X384251D01*
G01X392125Y79000D02*
Y7874D01*
G02X384251Y0I-7874J0D01*
G01X392125Y75995D02*
Y637220D01*
G01X384251Y686220D02*
G02X392125Y678346I0J-7874D01*
G01Y637220D01*
G01Y696220D02*
Y736220D01*
G01X385125Y724720D02*
X392125Y726220D01*
X385125Y727720D01*
Y724720D01*
G01X401968Y0D02*
X441755D01*
G01X402125D02*
X442125D01*
G01X402125Y686220D02*
X442125D01*
G01X432125Y291585D02*
Y0D01*
G01X430625Y7000D02*
X432125Y0D01*
X433625Y7000D01*
X430625D01*
G01X450875Y309160D02*
Y304510D01*
X438375D01*
Y309160D01*
G01X450875Y377360D02*
Y382010D01*
X438375D01*
Y377360D01*
G01X432125Y394635D02*
Y686220D01*
G01X433625Y679220D02*
X432125Y686220D01*
X430625Y679220D01*
X433625D01*
G01X611688Y95342D02*
X611941Y95592D01*
X612131Y96008D01*
X612258Y96592D01*
X612131Y97092D01*
X611878Y97425D01*
X611434Y97675D01*
X609724D01*
Y92675D01*
X611814D01*
X612258Y93008D01*
X612511Y93508D01*
X612638Y94092D01*
X612511Y94675D01*
X612131Y95175D01*
X611688Y95342D01*
X609724D01*
G01X615394Y92675D02*
Y96008D01*
G01Y95342D02*
X615711Y95675D01*
X616028Y95925D01*
X616471Y96008D01*
X616788Y95925D01*
X617168Y95675D01*
G01X620431Y94925D02*
X622458D01*
X622268Y95508D01*
X621951Y95842D01*
X621508Y96008D01*
X621064Y95925D01*
X620684Y95675D01*
X620431Y95092D01*
X620304Y94592D01*
Y94092D01*
X620431Y93592D01*
X620748Y93092D01*
X621128Y92758D01*
X621571Y92675D01*
X622014Y92842D01*
X622458Y93342D01*
G01X627621Y92675D02*
Y96008D01*
G01Y95425D02*
X627368Y95758D01*
X626988Y95925D01*
X626544Y96008D01*
X626101Y95842D01*
X625721Y95508D01*
X625468Y95008D01*
X625341Y94342D01*
X625468Y93675D01*
X625721Y93175D01*
X626101Y92842D01*
X626544Y92675D01*
X626988Y92758D01*
X627368Y93008D01*
X627621Y93342D01*
G01X630504Y92675D02*
Y97675D01*
G01X632531Y96008D02*
X630504Y94092D01*
G01X631328Y94842D02*
X632658Y92675D01*
G01X636681Y97675D02*
Y92675D01*
G01X635794Y96008D02*
X637568D01*
G01X642921Y92675D02*
Y96008D01*
G01Y95425D02*
X642668Y95758D01*
X642288Y95925D01*
X641844Y96008D01*
X641401Y95842D01*
X641021Y95508D01*
X640768Y95008D01*
X640641Y94342D01*
X640768Y93675D01*
X641021Y93175D01*
X641401Y92842D01*
X641844Y92675D01*
X642288Y92758D01*
X642668Y93008D01*
X642921Y93342D01*
G01X645741Y92675D02*
Y97675D01*
G01Y95175D02*
X646058Y95675D01*
X646438Y95925D01*
X646818Y96008D01*
X647388Y95842D01*
X647768Y95508D01*
X648021Y94925D01*
Y94258D01*
X647894Y93592D01*
X647641Y93092D01*
X647198Y92758D01*
X646818Y92675D01*
X646438Y92758D01*
X646058Y93008D01*
X645741Y93425D01*
G01X651981Y92508D02*
X651854Y92592D01*
Y92758D01*
X651981Y92842D01*
X652108Y92758D01*
Y92592D01*
X651981Y92508D01*
G01Y94758D02*
X651854Y94842D01*
Y95008D01*
X651981Y95092D01*
X652108Y95008D01*
Y94842D01*
X651981Y94758D01*
G01X686478Y159205D02*
Y164205D01*
X688884D01*
G01X687998Y161788D02*
X686478D01*
G01X692781Y159205D02*
X692401Y159288D01*
X692021Y159622D01*
X691768Y160205D01*
X691641Y160872D01*
X691768Y161538D01*
X692021Y162122D01*
X692401Y162455D01*
X692781Y162538D01*
X693161Y162455D01*
X693541Y162122D01*
X693794Y161538D01*
X693858Y160872D01*
X693794Y160205D01*
X693541Y159622D01*
X693161Y159288D01*
X692781Y159205D01*
G01X696994D02*
Y162538D01*
G01Y161872D02*
X697311Y162205D01*
X697628Y162455D01*
X698071Y162538D01*
X698388Y162455D01*
X698768Y162205D01*
G01X706814Y159205D02*
Y164205D01*
X708334D01*
X708841Y163955D01*
X709221Y163372D01*
X709348Y162705D01*
X709221Y162038D01*
X708904Y161538D01*
X708334Y161288D01*
X706814D01*
G01X714321Y159205D02*
Y162538D01*
G01Y161955D02*
X714068Y162288D01*
X713688Y162455D01*
X713244Y162538D01*
X712801Y162372D01*
X712421Y162038D01*
X712168Y161538D01*
X712041Y160872D01*
X712168Y160205D01*
X712421Y159705D01*
X712801Y159372D01*
X713244Y159205D01*
X713688Y159288D01*
X714068Y159538D01*
X714321Y159872D01*
G01X717204Y159205D02*
Y162538D01*
G01Y161705D02*
X717458Y162122D01*
X717838Y162455D01*
X718344Y162538D01*
X718788Y162455D01*
X719168Y162122D01*
X719358Y161538D01*
Y159205D01*
G01X722431Y161455D02*
X724458D01*
X724268Y162038D01*
X723951Y162372D01*
X723508Y162538D01*
X723064Y162455D01*
X722684Y162205D01*
X722431Y161622D01*
X722304Y161122D01*
Y160622D01*
X722431Y160122D01*
X722748Y159622D01*
X723128Y159288D01*
X723571Y159205D01*
X724014Y159372D01*
X724458Y159872D01*
G01X728481Y159205D02*
Y164205D01*
G01X739188Y161872D02*
X739441Y162122D01*
X739631Y162538D01*
X739758Y163122D01*
X739631Y163622D01*
X739378Y163955D01*
X738934Y164205D01*
X737224D01*
Y159205D01*
X739314D01*
X739758Y159538D01*
X740011Y160038D01*
X740138Y160622D01*
X740011Y161205D01*
X739631Y161705D01*
X739188Y161872D01*
X737224D01*
G01X743781Y159205D02*
X743401Y159288D01*
X743021Y159622D01*
X742768Y160205D01*
X742641Y160872D01*
X742768Y161538D01*
X743021Y162122D01*
X743401Y162455D01*
X743781Y162538D01*
X744161Y162455D01*
X744541Y162122D01*
X744794Y161538D01*
X744858Y160872D01*
X744794Y160205D01*
X744541Y159622D01*
X744161Y159288D01*
X743781Y159205D01*
G01X750021D02*
Y162538D01*
G01Y161955D02*
X749768Y162288D01*
X749388Y162455D01*
X748944Y162538D01*
X748501Y162372D01*
X748121Y162038D01*
X747868Y161538D01*
X747741Y160872D01*
X747868Y160205D01*
X748121Y159705D01*
X748501Y159372D01*
X748944Y159205D01*
X749388Y159288D01*
X749768Y159538D01*
X750021Y159872D01*
G01X753094Y159205D02*
Y162538D01*
G01Y161872D02*
X753411Y162205D01*
X753728Y162455D01*
X754171Y162538D01*
X754488Y162455D01*
X754868Y162205D01*
G01X760221Y164205D02*
Y159205D01*
G01Y159955D02*
X759968Y159538D01*
X759588Y159288D01*
X759144Y159205D01*
X758638Y159372D01*
X758258Y159788D01*
X758004Y160288D01*
X757941Y160872D01*
X758004Y161455D01*
X758258Y161955D01*
X758638Y162372D01*
X759144Y162538D01*
X759588Y162455D01*
X759904Y162288D01*
X760221Y161955D01*
G01X687681Y176805D02*
Y171805D01*
G01X686224Y176805D02*
X689138D01*
G01X692781Y171805D02*
X692401Y171888D01*
X692021Y172222D01*
X691768Y172805D01*
X691641Y173472D01*
X691768Y174138D01*
X692021Y174722D01*
X692401Y175055D01*
X692781Y175138D01*
X693161Y175055D01*
X693541Y174722D01*
X693794Y174138D01*
X693858Y173472D01*
X693794Y172805D01*
X693541Y172222D01*
X693161Y171888D01*
X692781Y171805D01*
G01X696741Y170138D02*
Y175138D01*
G01Y174388D02*
X697058Y174805D01*
X697374Y175055D01*
X697881Y175138D01*
X698324Y175055D01*
X698768Y174638D01*
X698958Y174055D01*
X699021Y173472D01*
X698958Y172888D01*
X698768Y172305D01*
X698388Y171972D01*
X697881Y171805D01*
X697438Y171888D01*
X696994Y172138D01*
X696741Y172472D01*
G01X706498Y171805D02*
X708081Y176805D01*
X709664Y171805D01*
G01X709094Y173555D02*
X707068D01*
G01X712104Y171805D02*
Y175138D01*
G01Y174305D02*
X712358Y174722D01*
X712738Y175055D01*
X713244Y175138D01*
X713688Y175055D01*
X714068Y174722D01*
X714258Y174138D01*
Y171805D01*
G01X719421Y176805D02*
Y171805D01*
G01Y172555D02*
X719168Y172138D01*
X718788Y171888D01*
X718344Y171805D01*
X717838Y171972D01*
X717458Y172388D01*
X717204Y172888D01*
X717141Y173472D01*
X717204Y174055D01*
X717458Y174555D01*
X717838Y174972D01*
X718344Y175138D01*
X718788Y175055D01*
X719104Y174888D01*
X719421Y174555D01*
G01X728988Y174472D02*
X729241Y174722D01*
X729431Y175138D01*
X729558Y175722D01*
X729431Y176222D01*
X729178Y176555D01*
X728734Y176805D01*
X727024D01*
Y171805D01*
X729114D01*
X729558Y172138D01*
X729811Y172638D01*
X729938Y173222D01*
X729811Y173805D01*
X729431Y174305D01*
X728988Y174472D01*
X727024D01*
G01X733581Y171805D02*
X733201Y171888D01*
X732821Y172222D01*
X732568Y172805D01*
X732441Y173472D01*
X732568Y174138D01*
X732821Y174722D01*
X733201Y175055D01*
X733581Y175138D01*
X733961Y175055D01*
X734341Y174722D01*
X734594Y174138D01*
X734658Y173472D01*
X734594Y172805D01*
X734341Y172222D01*
X733961Y171888D01*
X733581Y171805D01*
G01X738681Y176805D02*
Y171805D01*
G01X737794Y175138D02*
X739568D01*
G01X743781Y176805D02*
Y171805D01*
G01X742894Y175138D02*
X744668D01*
G01X748881Y171805D02*
X748501Y171888D01*
X748121Y172222D01*
X747868Y172805D01*
X747741Y173472D01*
X747868Y174138D01*
X748121Y174722D01*
X748501Y175055D01*
X748881Y175138D01*
X749261Y175055D01*
X749641Y174722D01*
X749894Y174138D01*
X749958Y173472D01*
X749894Y172805D01*
X749641Y172222D01*
X749261Y171888D01*
X748881Y171805D01*
G01X752081D02*
Y175138D01*
G01Y174222D02*
X752271Y174638D01*
X752588Y174972D01*
X753031Y175138D01*
X753474Y174972D01*
X753791Y174638D01*
X753981Y174222D01*
Y171805D01*
G01Y174222D02*
X754171Y174638D01*
X754488Y174972D01*
X754931Y175138D01*
X755374Y174972D01*
X755691Y174638D01*
X755881Y174138D01*
Y171805D01*
G01X762851Y172472D02*
X763358Y172055D01*
X763928Y171805D01*
X764434D01*
X764941Y172055D01*
X765321Y172472D01*
X765511Y173055D01*
X765384Y173638D01*
X765068Y174138D01*
X764498Y174472D01*
X763738Y174638D01*
X763294Y174972D01*
X763104Y175555D01*
X763231Y176138D01*
X763548Y176555D01*
X763991Y176805D01*
X764434D01*
X764878Y176638D01*
X765258Y176222D01*
G01X769281Y175138D02*
Y171805D01*
G01Y176472D02*
X769154Y176555D01*
Y176722D01*
X769281Y176805D01*
X769408Y176722D01*
Y176555D01*
X769281Y176472D01*
G01X775521Y176805D02*
Y171805D01*
G01Y172555D02*
X775268Y172138D01*
X774888Y171888D01*
X774444Y171805D01*
X773938Y171972D01*
X773558Y172388D01*
X773304Y172888D01*
X773241Y173472D01*
X773304Y174055D01*
X773558Y174555D01*
X773938Y174972D01*
X774444Y175138D01*
X774888Y175055D01*
X775204Y174888D01*
X775521Y174555D01*
G01X778531Y174055D02*
X780558D01*
X780368Y174638D01*
X780051Y174972D01*
X779608Y175138D01*
X779164Y175055D01*
X778784Y174805D01*
X778531Y174222D01*
X778404Y173722D01*
Y173222D01*
X778531Y172722D01*
X778848Y172222D01*
X779228Y171888D01*
X779671Y171805D01*
X780114Y171972D01*
X780558Y172472D01*
G01X686478Y159205D02*
Y164205D01*
X688884D01*
G01X687998Y161788D02*
X686478D01*
G01X692781Y159205D02*
X692401Y159288D01*
X692021Y159622D01*
X691768Y160205D01*
X691641Y160872D01*
X691768Y161538D01*
X692021Y162122D01*
X692401Y162455D01*
X692781Y162538D01*
X693161Y162455D01*
X693541Y162122D01*
X693794Y161538D01*
X693858Y160872D01*
X693794Y160205D01*
X693541Y159622D01*
X693161Y159288D01*
X692781Y159205D01*
G01X696994D02*
Y162538D01*
G01Y161872D02*
X697311Y162205D01*
X697628Y162455D01*
X698071Y162538D01*
X698388Y162455D01*
X698768Y162205D01*
G01X706814Y159205D02*
Y164205D01*
X708334D01*
X708841Y163955D01*
X709221Y163372D01*
X709348Y162705D01*
X709221Y162038D01*
X708904Y161538D01*
X708334Y161288D01*
X706814D01*
G01X714321Y159205D02*
Y162538D01*
G01Y161955D02*
X714068Y162288D01*
X713688Y162455D01*
X713244Y162538D01*
X712801Y162372D01*
X712421Y162038D01*
X712168Y161538D01*
X712041Y160872D01*
X712168Y160205D01*
X712421Y159705D01*
X712801Y159372D01*
X713244Y159205D01*
X713688Y159288D01*
X714068Y159538D01*
X714321Y159872D01*
G01X717204Y159205D02*
Y162538D01*
G01Y161705D02*
X717458Y162122D01*
X717838Y162455D01*
X718344Y162538D01*
X718788Y162455D01*
X719168Y162122D01*
X719358Y161538D01*
Y159205D01*
G01X722431Y161455D02*
X724458D01*
X724268Y162038D01*
X723951Y162372D01*
X723508Y162538D01*
X723064Y162455D01*
X722684Y162205D01*
X722431Y161622D01*
X722304Y161122D01*
Y160622D01*
X722431Y160122D01*
X722748Y159622D01*
X723128Y159288D01*
X723571Y159205D01*
X724014Y159372D01*
X724458Y159872D01*
G01X728481Y159205D02*
Y164205D01*
G01X739188Y161872D02*
X739441Y162122D01*
X739631Y162538D01*
X739758Y163122D01*
X739631Y163622D01*
X739378Y163955D01*
X738934Y164205D01*
X737224D01*
Y159205D01*
X739314D01*
X739758Y159538D01*
X740011Y160038D01*
X740138Y160622D01*
X740011Y161205D01*
X739631Y161705D01*
X739188Y161872D01*
X737224D01*
G01X743781Y159205D02*
X743401Y159288D01*
X743021Y159622D01*
X742768Y160205D01*
X742641Y160872D01*
X742768Y161538D01*
X743021Y162122D01*
X743401Y162455D01*
X743781Y162538D01*
X744161Y162455D01*
X744541Y162122D01*
X744794Y161538D01*
X744858Y160872D01*
X744794Y160205D01*
X744541Y159622D01*
X744161Y159288D01*
X743781Y159205D01*
G01X750021D02*
Y162538D01*
G01Y161955D02*
X749768Y162288D01*
X749388Y162455D01*
X748944Y162538D01*
X748501Y162372D01*
X748121Y162038D01*
X747868Y161538D01*
X747741Y160872D01*
X747868Y160205D01*
X748121Y159705D01*
X748501Y159372D01*
X748944Y159205D01*
X749388Y159288D01*
X749768Y159538D01*
X750021Y159872D01*
G01X753094Y159205D02*
Y162538D01*
G01Y161872D02*
X753411Y162205D01*
X753728Y162455D01*
X754171Y162538D01*
X754488Y162455D01*
X754868Y162205D01*
G01X760221Y164205D02*
Y159205D01*
G01Y159955D02*
X759968Y159538D01*
X759588Y159288D01*
X759144Y159205D01*
X758638Y159372D01*
X758258Y159788D01*
X758004Y160288D01*
X757941Y160872D01*
X758004Y161455D01*
X758258Y161955D01*
X758638Y162372D01*
X759144Y162538D01*
X759588Y162455D01*
X759904Y162288D01*
X760221Y161955D01*
G01X609978Y197005D02*
Y202005D01*
X612384D01*
G01X611498Y199588D02*
X609978D01*
G01X616281Y200338D02*
Y197005D01*
G01Y201672D02*
X616154Y201755D01*
Y201922D01*
X616281Y202005D01*
X616408Y201922D01*
Y201755D01*
X616281Y201672D01*
G01X622521Y202005D02*
Y197005D01*
G01Y197755D02*
X622268Y197338D01*
X621888Y197088D01*
X621444Y197005D01*
X620938Y197172D01*
X620558Y197588D01*
X620304Y198088D01*
X620241Y198672D01*
X620304Y199255D01*
X620558Y199755D01*
X620938Y200172D01*
X621444Y200338D01*
X621888Y200255D01*
X622204Y200088D01*
X622521Y199755D01*
G01X625404Y200338D02*
Y198005D01*
X625658Y197422D01*
X626038Y197088D01*
X626481Y197005D01*
X626924Y197088D01*
X627304Y197422D01*
X627558Y198005D01*
G01Y197005D02*
Y200338D01*
G01X632594Y199922D02*
X632151Y200255D01*
X631771Y200338D01*
X631264Y200172D01*
X630884Y199838D01*
X630631Y199255D01*
X630568Y198672D01*
X630631Y198088D01*
X630884Y197588D01*
X631264Y197172D01*
X631771Y197005D01*
X632214Y197172D01*
X632594Y197505D01*
G01X636681Y200338D02*
Y197005D01*
G01Y201672D02*
X636554Y201755D01*
Y201922D01*
X636681Y202005D01*
X636808Y201922D01*
Y201755D01*
X636681Y201672D01*
G01X642921Y197005D02*
Y200338D01*
G01Y199755D02*
X642668Y200088D01*
X642288Y200255D01*
X641844Y200338D01*
X641401Y200172D01*
X641021Y199838D01*
X640768Y199338D01*
X640641Y198672D01*
X640768Y198005D01*
X641021Y197505D01*
X641401Y197172D01*
X641844Y197005D01*
X642288Y197088D01*
X642668Y197338D01*
X642921Y197672D01*
G01X646881Y197005D02*
Y202005D01*
G01X655434Y197005D02*
Y202005D01*
X657081Y197838D01*
X658728Y202005D01*
Y197005D01*
G01X663321D02*
Y200338D01*
G01Y199755D02*
X663068Y200088D01*
X662688Y200255D01*
X662244Y200338D01*
X661801Y200172D01*
X661421Y199838D01*
X661168Y199338D01*
X661041Y198672D01*
X661168Y198005D01*
X661421Y197505D01*
X661801Y197172D01*
X662244Y197005D01*
X662688Y197088D01*
X663068Y197338D01*
X663321Y197672D01*
G01X666394Y197005D02*
Y200338D01*
G01Y199672D02*
X666711Y200005D01*
X667028Y200255D01*
X667471Y200338D01*
X667788Y200255D01*
X668168Y200005D01*
G01X671304Y197005D02*
Y202005D01*
G01X673331Y200338D02*
X671304Y198422D01*
G01X672128Y199172D02*
X673458Y197005D01*
G01X677481Y196838D02*
X677354Y196922D01*
Y197088D01*
X677481Y197172D01*
X677608Y197088D01*
Y196922D01*
X677481Y196838D01*
G01Y199088D02*
X677354Y199172D01*
Y199338D01*
X677481Y199422D01*
X677608Y199338D01*
Y199172D01*
X677481Y199088D01*
G01X686288Y197005D02*
Y202005D01*
X687554D01*
X688061Y201755D01*
X688441Y201422D01*
X688758Y200922D01*
X689011Y200338D01*
X689074Y199505D01*
X689011Y198672D01*
X688758Y198088D01*
X688441Y197588D01*
X688061Y197255D01*
X687554Y197005D01*
X686288D01*
G01X692781Y200338D02*
Y197005D01*
G01Y201672D02*
X692654Y201755D01*
Y201922D01*
X692781Y202005D01*
X692908Y201922D01*
Y201755D01*
X692781Y201672D01*
G01X699021Y197005D02*
Y200338D01*
G01Y199755D02*
X698768Y200088D01*
X698388Y200255D01*
X697944Y200338D01*
X697501Y200172D01*
X697121Y199838D01*
X696868Y199338D01*
X696741Y198672D01*
X696868Y198005D01*
X697121Y197505D01*
X697501Y197172D01*
X697944Y197005D01*
X698388Y197088D01*
X698768Y197338D01*
X699021Y197672D01*
G01X701081Y197005D02*
Y200338D01*
G01Y199422D02*
X701271Y199838D01*
X701588Y200172D01*
X702031Y200338D01*
X702474Y200172D01*
X702791Y199838D01*
X702981Y199422D01*
Y197005D01*
G01Y199422D02*
X703171Y199838D01*
X703488Y200172D01*
X703931Y200338D01*
X704374Y200172D01*
X704691Y199838D01*
X704881Y199338D01*
Y197005D01*
G01X707131Y199255D02*
X709158D01*
X708968Y199838D01*
X708651Y200172D01*
X708208Y200338D01*
X707764Y200255D01*
X707384Y200005D01*
X707131Y199422D01*
X707004Y198922D01*
Y198422D01*
X707131Y197922D01*
X707448Y197422D01*
X707828Y197088D01*
X708271Y197005D01*
X708714Y197172D01*
X709158Y197672D01*
G01X713181Y202005D02*
Y197005D01*
G01X712294Y200338D02*
X714068D01*
G01X717331Y199255D02*
X719358D01*
X719168Y199838D01*
X718851Y200172D01*
X718408Y200338D01*
X717964Y200255D01*
X717584Y200005D01*
X717331Y199422D01*
X717204Y198922D01*
Y198422D01*
X717331Y197922D01*
X717648Y197422D01*
X718028Y197088D01*
X718471Y197005D01*
X718914Y197172D01*
X719358Y197672D01*
G01X722494Y197005D02*
Y200338D01*
G01Y199672D02*
X722811Y200005D01*
X723128Y200255D01*
X723571Y200338D01*
X723888Y200255D01*
X724268Y200005D01*
G01X733581Y197005D02*
Y202005D01*
X732821Y201005D01*
G01Y197005D02*
X734341D01*
G01X736781D02*
Y200338D01*
G01Y199422D02*
X736971Y199838D01*
X737288Y200172D01*
X737731Y200338D01*
X738174Y200172D01*
X738491Y199838D01*
X738681Y199422D01*
Y197005D01*
G01Y199422D02*
X738871Y199838D01*
X739188Y200172D01*
X739631Y200338D01*
X740074Y200172D01*
X740391Y199838D01*
X740581Y199338D01*
Y197005D01*
G01X741881D02*
Y200338D01*
G01Y199422D02*
X742071Y199838D01*
X742388Y200172D01*
X742831Y200338D01*
X743274Y200172D01*
X743591Y199838D01*
X743781Y199422D01*
Y197005D01*
G01Y199422D02*
X743971Y199838D01*
X744288Y200172D01*
X744731Y200338D01*
X745174Y200172D01*
X745491Y199838D01*
X745681Y199338D01*
Y197005D01*
G01X755374Y201588D02*
X754994Y201838D01*
X754551Y202005D01*
X754044D01*
X753474Y201755D01*
X753031Y201338D01*
X752714Y200838D01*
X752461Y200005D01*
X752398Y199255D01*
X752524Y198505D01*
X752714Y198005D01*
X753094Y197505D01*
X753538Y197172D01*
X753981Y197005D01*
X754424D01*
X754868Y197172D01*
X755248Y197422D01*
X755564Y197755D01*
G01X759081Y197005D02*
X758701Y197088D01*
X758321Y197422D01*
X758068Y198005D01*
X757941Y198672D01*
X758068Y199338D01*
X758321Y199922D01*
X758701Y200255D01*
X759081Y200338D01*
X759461Y200255D01*
X759841Y199922D01*
X760094Y199338D01*
X760158Y198672D01*
X760094Y198005D01*
X759841Y197422D01*
X759461Y197088D01*
X759081Y197005D01*
G01X763041Y195338D02*
Y200338D01*
G01Y199588D02*
X763358Y200005D01*
X763674Y200255D01*
X764181Y200338D01*
X764624Y200255D01*
X765068Y199838D01*
X765258Y199255D01*
X765321Y198672D01*
X765258Y198088D01*
X765068Y197505D01*
X764688Y197172D01*
X764181Y197005D01*
X763738Y197088D01*
X763294Y197338D01*
X763041Y197672D01*
G01X768141Y195338D02*
Y200338D01*
G01Y199588D02*
X768458Y200005D01*
X768774Y200255D01*
X769281Y200338D01*
X769724Y200255D01*
X770168Y199838D01*
X770358Y199255D01*
X770421Y198672D01*
X770358Y198088D01*
X770168Y197505D01*
X769788Y197172D01*
X769281Y197005D01*
X768838Y197088D01*
X768394Y197338D01*
X768141Y197672D01*
G01X773431Y199255D02*
X775458D01*
X775268Y199838D01*
X774951Y200172D01*
X774508Y200338D01*
X774064Y200255D01*
X773684Y200005D01*
X773431Y199422D01*
X773304Y198922D01*
Y198422D01*
X773431Y197922D01*
X773748Y197422D01*
X774128Y197088D01*
X774571Y197005D01*
X775014Y197172D01*
X775458Y197672D01*
G01X778594Y197005D02*
Y200338D01*
G01Y199672D02*
X778911Y200005D01*
X779228Y200255D01*
X779671Y200338D01*
X779988Y200255D01*
X780368Y200005D01*
G01X686288Y184405D02*
Y189405D01*
X687554D01*
X688061Y189155D01*
X688441Y188822D01*
X688758Y188322D01*
X689011Y187738D01*
X689074Y186905D01*
X689011Y186072D01*
X688758Y185488D01*
X688441Y184988D01*
X688061Y184655D01*
X687554Y184405D01*
X686288D01*
G01X692781Y187738D02*
Y184405D01*
G01Y189072D02*
X692654Y189155D01*
Y189322D01*
X692781Y189405D01*
X692908Y189322D01*
Y189155D01*
X692781Y189072D01*
G01X699021Y184405D02*
Y187738D01*
G01Y187155D02*
X698768Y187488D01*
X698388Y187655D01*
X697944Y187738D01*
X697501Y187572D01*
X697121Y187238D01*
X696868Y186738D01*
X696741Y186072D01*
X696868Y185405D01*
X697121Y184905D01*
X697501Y184572D01*
X697944Y184405D01*
X698388Y184488D01*
X698768Y184738D01*
X699021Y185072D01*
G01X701081Y184405D02*
Y187738D01*
G01Y186822D02*
X701271Y187238D01*
X701588Y187572D01*
X702031Y187738D01*
X702474Y187572D01*
X702791Y187238D01*
X702981Y186822D01*
Y184405D01*
G01Y186822D02*
X703171Y187238D01*
X703488Y187572D01*
X703931Y187738D01*
X704374Y187572D01*
X704691Y187238D01*
X704881Y186738D01*
Y184405D01*
G01X707131Y186655D02*
X709158D01*
X708968Y187238D01*
X708651Y187572D01*
X708208Y187738D01*
X707764Y187655D01*
X707384Y187405D01*
X707131Y186822D01*
X707004Y186322D01*
Y185822D01*
X707131Y185322D01*
X707448Y184822D01*
X707828Y184488D01*
X708271Y184405D01*
X708714Y184572D01*
X709158Y185072D01*
G01X713181Y189405D02*
Y184405D01*
G01X712294Y187738D02*
X714068D01*
G01X717331Y186655D02*
X719358D01*
X719168Y187238D01*
X718851Y187572D01*
X718408Y187738D01*
X717964Y187655D01*
X717584Y187405D01*
X717331Y186822D01*
X717204Y186322D01*
Y185822D01*
X717331Y185322D01*
X717648Y184822D01*
X718028Y184488D01*
X718471Y184405D01*
X718914Y184572D01*
X719358Y185072D01*
G01X722494Y184405D02*
Y187738D01*
G01Y187072D02*
X722811Y187405D01*
X723128Y187655D01*
X723571Y187738D01*
X723888Y187655D01*
X724268Y187405D01*
G01X732188Y185405D02*
X732568Y184822D01*
X733074Y184488D01*
X733644Y184405D01*
X734151Y184488D01*
X734658Y184905D01*
X734974Y185405D01*
X735038Y185905D01*
X734911Y186488D01*
X734468Y186905D01*
X734024Y187072D01*
X733454D01*
G01X734024D02*
X734404Y187322D01*
X734721Y187738D01*
X734848Y188238D01*
X734721Y188738D01*
X734404Y189155D01*
X733834Y189405D01*
X733264Y189322D01*
X732694Y188988D01*
G01X736781Y184405D02*
Y187738D01*
G01Y186822D02*
X736971Y187238D01*
X737288Y187572D01*
X737731Y187738D01*
X738174Y187572D01*
X738491Y187238D01*
X738681Y186822D01*
Y184405D01*
G01Y186822D02*
X738871Y187238D01*
X739188Y187572D01*
X739631Y187738D01*
X740074Y187572D01*
X740391Y187238D01*
X740581Y186738D01*
Y184405D01*
G01X741881D02*
Y187738D01*
G01Y186822D02*
X742071Y187238D01*
X742388Y187572D01*
X742831Y187738D01*
X743274Y187572D01*
X743591Y187238D01*
X743781Y186822D01*
Y184405D01*
G01Y186822D02*
X743971Y187238D01*
X744288Y187572D01*
X744731Y187738D01*
X745174Y187572D01*
X745491Y187238D01*
X745681Y186738D01*
Y184405D01*
G01X752651Y185072D02*
X753158Y184655D01*
X753728Y184405D01*
X754234D01*
X754741Y184655D01*
X755121Y185072D01*
X755311Y185655D01*
X755184Y186238D01*
X754868Y186738D01*
X754298Y187072D01*
X753538Y187238D01*
X753094Y187572D01*
X752904Y188155D01*
X753031Y188738D01*
X753348Y189155D01*
X753791Y189405D01*
X754234D01*
X754678Y189238D01*
X755058Y188822D01*
G01X759081Y184405D02*
X758701Y184488D01*
X758321Y184822D01*
X758068Y185405D01*
X757941Y186072D01*
X758068Y186738D01*
X758321Y187322D01*
X758701Y187655D01*
X759081Y187738D01*
X759461Y187655D01*
X759841Y187322D01*
X760094Y186738D01*
X760158Y186072D01*
X760094Y185405D01*
X759841Y184822D01*
X759461Y184488D01*
X759081Y184405D01*
G01X764181D02*
Y189405D01*
G01X770421D02*
Y184405D01*
G01Y185155D02*
X770168Y184738D01*
X769788Y184488D01*
X769344Y184405D01*
X768838Y184572D01*
X768458Y184988D01*
X768204Y185488D01*
X768141Y186072D01*
X768204Y186655D01*
X768458Y187155D01*
X768838Y187572D01*
X769344Y187738D01*
X769788Y187655D01*
X770104Y187488D01*
X770421Y187155D01*
G01X773431Y186655D02*
X775458D01*
X775268Y187238D01*
X774951Y187572D01*
X774508Y187738D01*
X774064Y187655D01*
X773684Y187405D01*
X773431Y186822D01*
X773304Y186322D01*
Y185822D01*
X773431Y185322D01*
X773748Y184822D01*
X774128Y184488D01*
X774571Y184405D01*
X775014Y184572D01*
X775458Y185072D01*
G01X778594Y184405D02*
Y187738D01*
G01Y187072D02*
X778911Y187405D01*
X779228Y187655D01*
X779671Y187738D01*
X779988Y187655D01*
X780368Y187405D01*
G01X782681Y184405D02*
Y187738D01*
G01Y186822D02*
X782871Y187238D01*
X783188Y187572D01*
X783631Y187738D01*
X784074Y187572D01*
X784391Y187238D01*
X784581Y186822D01*
Y184405D01*
G01Y186822D02*
X784771Y187238D01*
X785088Y187572D01*
X785531Y187738D01*
X785974Y187572D01*
X786291Y187238D01*
X786481Y186738D01*
Y184405D01*
G01X790821D02*
Y187738D01*
G01Y187155D02*
X790568Y187488D01*
X790188Y187655D01*
X789744Y187738D01*
X789301Y187572D01*
X788921Y187238D01*
X788668Y186738D01*
X788541Y186072D01*
X788668Y185405D01*
X788921Y184905D01*
X789301Y184572D01*
X789744Y184405D01*
X790188Y184488D01*
X790568Y184738D01*
X790821Y185072D01*
G01X793831Y184988D02*
X794148Y184655D01*
X794591Y184405D01*
X794971D01*
X795351Y184572D01*
X795604Y184822D01*
X795731Y185155D01*
X795668Y185655D01*
X795414Y185905D01*
X794274Y186405D01*
X794021Y186988D01*
X794148Y187405D01*
X794401Y187655D01*
X794781Y187738D01*
X795161Y187655D01*
X795541Y187405D01*
G01X798804Y184405D02*
Y189405D01*
G01X800831Y187738D02*
X798804Y185822D01*
G01X799628Y186572D02*
X800958Y184405D01*
G01X683369Y258697D02*
Y253697D01*
G01X681912Y258697D02*
X684826D01*
G01X688469Y253697D02*
X688089Y253780D01*
X687709Y254114D01*
X687456Y254697D01*
X687329Y255364D01*
X687456Y256030D01*
X687709Y256614D01*
X688089Y256947D01*
X688469Y257030D01*
X688849Y256947D01*
X689229Y256614D01*
X689482Y256030D01*
X689546Y255364D01*
X689482Y254697D01*
X689229Y254114D01*
X688849Y253780D01*
X688469Y253697D01*
G01X693569D02*
Y258697D01*
G01X697719Y255947D02*
X699746D01*
X699556Y256530D01*
X699239Y256864D01*
X698796Y257030D01*
X698352Y256947D01*
X697972Y256697D01*
X697719Y256114D01*
X697592Y255614D01*
Y255114D01*
X697719Y254614D01*
X698036Y254114D01*
X698416Y253780D01*
X698859Y253697D01*
X699302Y253864D01*
X699746Y254364D01*
G01X702882Y253697D02*
Y257030D01*
G01Y256364D02*
X703199Y256697D01*
X703516Y256947D01*
X703959Y257030D01*
X704276Y256947D01*
X704656Y256697D01*
G01X710009Y253697D02*
Y257030D01*
G01Y256447D02*
X709756Y256780D01*
X709376Y256947D01*
X708932Y257030D01*
X708489Y256864D01*
X708109Y256530D01*
X707856Y256030D01*
X707729Y255364D01*
X707856Y254697D01*
X708109Y254197D01*
X708489Y253864D01*
X708932Y253697D01*
X709376Y253780D01*
X709756Y254030D01*
X710009Y254364D01*
G01X712892Y253697D02*
Y257030D01*
G01Y256197D02*
X713146Y256614D01*
X713526Y256947D01*
X714032Y257030D01*
X714476Y256947D01*
X714856Y256614D01*
X715046Y256030D01*
Y253697D01*
G01X720082Y256614D02*
X719639Y256947D01*
X719259Y257030D01*
X718752Y256864D01*
X718372Y256530D01*
X718119Y255947D01*
X718056Y255364D01*
X718119Y254780D01*
X718372Y254280D01*
X718752Y253864D01*
X719259Y253697D01*
X719702Y253864D01*
X720082Y254197D01*
G01X723219Y255947D02*
X725246D01*
X725056Y256530D01*
X724739Y256864D01*
X724296Y257030D01*
X723852Y256947D01*
X723472Y256697D01*
X723219Y256114D01*
X723092Y255614D01*
Y255114D01*
X723219Y254614D01*
X723536Y254114D01*
X723916Y253780D01*
X724359Y253697D01*
X724802Y253864D01*
X725246Y254364D01*
G01X733672Y255364D02*
X735192D01*
G01X734369Y256447D02*
Y254280D01*
G01X739469Y258697D02*
X738962Y258530D01*
X738582Y258114D01*
X738329Y257614D01*
X738139Y256947D01*
X738076Y256197D01*
X738139Y255447D01*
X738329Y254780D01*
X738582Y254280D01*
X738962Y253864D01*
X739469Y253697D01*
X739976Y253864D01*
X740356Y254280D01*
X740609Y254780D01*
X740799Y255447D01*
X740862Y256197D01*
X740799Y256947D01*
X740609Y257614D01*
X740356Y258114D01*
X739976Y258530D01*
X739469Y258697D01*
G01X744569Y253530D02*
X744442Y253614D01*
Y253780D01*
X744569Y253864D01*
X744696Y253780D01*
Y253614D01*
X744569Y253530D01*
G01X749669Y258697D02*
X749162Y258530D01*
X748782Y258114D01*
X748529Y257614D01*
X748339Y256947D01*
X748276Y256197D01*
X748339Y255447D01*
X748529Y254780D01*
X748782Y254280D01*
X749162Y253864D01*
X749669Y253697D01*
X750176Y253864D01*
X750556Y254280D01*
X750809Y254780D01*
X750999Y255447D01*
X751062Y256197D01*
X750999Y256947D01*
X750809Y257614D01*
X750556Y258114D01*
X750176Y258530D01*
X749669Y258697D01*
G01X753376Y254447D02*
X753756Y254030D01*
X754199Y253780D01*
X754769Y253697D01*
X755339Y253864D01*
X755782Y254197D01*
X756099Y254780D01*
X756162Y255447D01*
X756036Y256114D01*
X755719Y256530D01*
X755276Y256864D01*
X754832Y256947D01*
X754389Y256864D01*
X753819Y256530D01*
X754009Y258697D01*
X755719D01*
G01X759869D02*
X759362Y258530D01*
X758982Y258114D01*
X758729Y257614D01*
X758539Y256947D01*
X758476Y256197D01*
X758539Y255447D01*
X758729Y254780D01*
X758982Y254280D01*
X759362Y253864D01*
X759869Y253697D01*
X760376Y253864D01*
X760756Y254280D01*
X761009Y254780D01*
X761199Y255447D01*
X761262Y256197D01*
X761199Y256947D01*
X761009Y257614D01*
X760756Y258114D01*
X760376Y258530D01*
X759869Y258697D01*
G01X764969Y253697D02*
X765412Y253780D01*
X765919Y254030D01*
X766236Y254447D01*
X766362Y255030D01*
X766236Y255614D01*
X765856Y256114D01*
X765286Y256364D01*
X764652D01*
X764272Y256530D01*
X763956Y256947D01*
X763829Y257530D01*
X764019Y258114D01*
X764462Y258530D01*
X764969Y258697D01*
X765476Y258530D01*
X765919Y258114D01*
X766109Y257530D01*
X765982Y256947D01*
X765666Y256530D01*
X765286Y256364D01*
X764652D01*
X764082Y256114D01*
X763702Y255614D01*
X763576Y255030D01*
X763702Y254447D01*
X764019Y254030D01*
X764526Y253780D01*
X764969Y253697D01*
G01X768169D02*
Y257030D01*
G01Y256114D02*
X768359Y256530D01*
X768676Y256864D01*
X769119Y257030D01*
X769562Y256864D01*
X769879Y256530D01*
X770069Y256114D01*
Y253697D01*
G01Y256114D02*
X770259Y256530D01*
X770576Y256864D01*
X771019Y257030D01*
X771462Y256864D01*
X771779Y256530D01*
X771969Y256030D01*
Y253697D01*
G01X773269D02*
Y257030D01*
G01Y256114D02*
X773459Y256530D01*
X773776Y256864D01*
X774219Y257030D01*
X774662Y256864D01*
X774979Y256530D01*
X775169Y256114D01*
Y253697D01*
G01Y256114D02*
X775359Y256530D01*
X775676Y256864D01*
X776119Y257030D01*
X776562Y256864D01*
X776879Y256530D01*
X777069Y256030D01*
Y253697D01*
G01X779129Y253530D02*
X781409Y258697D01*
G01X784546Y255364D02*
X786192D01*
G01X790469Y258697D02*
X789962Y258530D01*
X789582Y258114D01*
X789329Y257614D01*
X789139Y256947D01*
X789076Y256197D01*
X789139Y255447D01*
X789329Y254780D01*
X789582Y254280D01*
X789962Y253864D01*
X790469Y253697D01*
X790976Y253864D01*
X791356Y254280D01*
X791609Y254780D01*
X791799Y255447D01*
X791862Y256197D01*
X791799Y256947D01*
X791609Y257614D01*
X791356Y258114D01*
X790976Y258530D01*
X790469Y258697D01*
G01X795569Y253530D02*
X795442Y253614D01*
Y253780D01*
X795569Y253864D01*
X795696Y253780D01*
Y253614D01*
X795569Y253530D01*
G01X800669Y258697D02*
X800162Y258530D01*
X799782Y258114D01*
X799529Y257614D01*
X799339Y256947D01*
X799276Y256197D01*
X799339Y255447D01*
X799529Y254780D01*
X799782Y254280D01*
X800162Y253864D01*
X800669Y253697D01*
X801176Y253864D01*
X801556Y254280D01*
X801809Y254780D01*
X801999Y255447D01*
X802062Y256197D01*
X801999Y256947D01*
X801809Y257614D01*
X801556Y258114D01*
X801176Y258530D01*
X800669Y258697D01*
G01X805769D02*
X805262Y258530D01*
X804882Y258114D01*
X804629Y257614D01*
X804439Y256947D01*
X804376Y256197D01*
X804439Y255447D01*
X804629Y254780D01*
X804882Y254280D01*
X805262Y253864D01*
X805769Y253697D01*
X806276Y253864D01*
X806656Y254280D01*
X806909Y254780D01*
X807099Y255447D01*
X807162Y256197D01*
X807099Y256947D01*
X806909Y257614D01*
X806656Y258114D01*
X806276Y258530D01*
X805769Y258697D01*
G01X810869D02*
X810362Y258530D01*
X809982Y258114D01*
X809729Y257614D01*
X809539Y256947D01*
X809476Y256197D01*
X809539Y255447D01*
X809729Y254780D01*
X809982Y254280D01*
X810362Y253864D01*
X810869Y253697D01*
X811376Y253864D01*
X811756Y254280D01*
X812009Y254780D01*
X812199Y255447D01*
X812262Y256197D01*
X812199Y256947D01*
X812009Y257614D01*
X811756Y258114D01*
X811376Y258530D01*
X810869Y258697D01*
G01X815969D02*
X815462Y258530D01*
X815082Y258114D01*
X814829Y257614D01*
X814639Y256947D01*
X814576Y256197D01*
X814639Y255447D01*
X814829Y254780D01*
X815082Y254280D01*
X815462Y253864D01*
X815969Y253697D01*
X816476Y253864D01*
X816856Y254280D01*
X817109Y254780D01*
X817299Y255447D01*
X817362Y256197D01*
X817299Y256947D01*
X817109Y257614D01*
X816856Y258114D01*
X816476Y258530D01*
X815969Y258697D01*
G01X819169Y253697D02*
Y257030D01*
G01Y256114D02*
X819359Y256530D01*
X819676Y256864D01*
X820119Y257030D01*
X820562Y256864D01*
X820879Y256530D01*
X821069Y256114D01*
Y253697D01*
G01Y256114D02*
X821259Y256530D01*
X821576Y256864D01*
X822019Y257030D01*
X822462Y256864D01*
X822779Y256530D01*
X822969Y256030D01*
Y253697D01*
G01X824269D02*
Y257030D01*
G01Y256114D02*
X824459Y256530D01*
X824776Y256864D01*
X825219Y257030D01*
X825662Y256864D01*
X825979Y256530D01*
X826169Y256114D01*
Y253697D01*
G01Y256114D02*
X826359Y256530D01*
X826676Y256864D01*
X827119Y257030D01*
X827562Y256864D01*
X827879Y256530D01*
X828069Y256030D01*
Y253697D01*
G01X611969Y271297D02*
Y266297D01*
G01X610512Y271297D02*
X613426D01*
G01X617069Y266297D02*
X616689Y266380D01*
X616309Y266714D01*
X616056Y267297D01*
X615929Y267964D01*
X616056Y268630D01*
X616309Y269214D01*
X616689Y269547D01*
X617069Y269630D01*
X617449Y269547D01*
X617829Y269214D01*
X618082Y268630D01*
X618146Y267964D01*
X618082Y267297D01*
X617829Y266714D01*
X617449Y266380D01*
X617069Y266297D01*
G01X622169D02*
X621789Y266380D01*
X621409Y266714D01*
X621156Y267297D01*
X621029Y267964D01*
X621156Y268630D01*
X621409Y269214D01*
X621789Y269547D01*
X622169Y269630D01*
X622549Y269547D01*
X622929Y269214D01*
X623182Y268630D01*
X623246Y267964D01*
X623182Y267297D01*
X622929Y266714D01*
X622549Y266380D01*
X622169Y266297D01*
G01X627269D02*
Y271297D01*
G01X632369Y269630D02*
Y266297D01*
G01Y270964D02*
X632242Y271047D01*
Y271214D01*
X632369Y271297D01*
X632496Y271214D01*
Y271047D01*
X632369Y270964D01*
G01X636392Y266297D02*
Y269630D01*
G01Y268797D02*
X636646Y269214D01*
X637026Y269547D01*
X637532Y269630D01*
X637976Y269547D01*
X638356Y269214D01*
X638546Y268630D01*
Y266297D01*
G01X641682Y265047D02*
X642126Y264714D01*
X642632Y264630D01*
X643076Y264714D01*
X643456Y265130D01*
X643709Y265714D01*
Y269630D01*
G01Y268964D02*
X643456Y269297D01*
X643076Y269547D01*
X642632Y269630D01*
X642126Y269464D01*
X641809Y269130D01*
X641556Y268547D01*
X641429Y267964D01*
X641492Y267464D01*
X641746Y266880D01*
X642126Y266464D01*
X642632Y266297D01*
X643012Y266380D01*
X643456Y266714D01*
X643709Y267047D01*
G01X651439Y266297D02*
Y271297D01*
G01X654099D02*
Y266297D01*
G01Y268797D02*
X651439D01*
G01X657869Y266297D02*
X657489Y266380D01*
X657109Y266714D01*
X656856Y267297D01*
X656729Y267964D01*
X656856Y268630D01*
X657109Y269214D01*
X657489Y269547D01*
X657869Y269630D01*
X658249Y269547D01*
X658629Y269214D01*
X658882Y268630D01*
X658946Y267964D01*
X658882Y267297D01*
X658629Y266714D01*
X658249Y266380D01*
X657869Y266297D01*
G01X662969D02*
Y271297D01*
G01X667119Y268547D02*
X669146D01*
X668956Y269130D01*
X668639Y269464D01*
X668196Y269630D01*
X667752Y269547D01*
X667372Y269297D01*
X667119Y268714D01*
X666992Y268214D01*
Y267714D01*
X667119Y267214D01*
X667436Y266714D01*
X667816Y266380D01*
X668259Y266297D01*
X668702Y266464D01*
X669146Y266964D01*
G01X673169Y266130D02*
X673042Y266214D01*
Y266380D01*
X673169Y266464D01*
X673296Y266380D01*
Y266214D01*
X673169Y266130D01*
G01Y268380D02*
X673042Y268464D01*
Y268630D01*
X673169Y268714D01*
X673296Y268630D01*
Y268464D01*
X673169Y268380D01*
G01X681976Y266297D02*
Y271297D01*
X683242D01*
X683749Y271047D01*
X684129Y270714D01*
X684446Y270214D01*
X684699Y269630D01*
X684762Y268797D01*
X684699Y267964D01*
X684446Y267380D01*
X684129Y266880D01*
X683749Y266547D01*
X683242Y266297D01*
X681976D01*
G01X688469Y269630D02*
Y266297D01*
G01Y270964D02*
X688342Y271047D01*
Y271214D01*
X688469Y271297D01*
X688596Y271214D01*
Y271047D01*
X688469Y270964D01*
G01X694709Y266297D02*
Y269630D01*
G01Y269047D02*
X694456Y269380D01*
X694076Y269547D01*
X693632Y269630D01*
X693189Y269464D01*
X692809Y269130D01*
X692556Y268630D01*
X692429Y267964D01*
X692556Y267297D01*
X692809Y266797D01*
X693189Y266464D01*
X693632Y266297D01*
X694076Y266380D01*
X694456Y266630D01*
X694709Y266964D01*
G01X696769Y266297D02*
Y269630D01*
G01Y268714D02*
X696959Y269130D01*
X697276Y269464D01*
X697719Y269630D01*
X698162Y269464D01*
X698479Y269130D01*
X698669Y268714D01*
Y266297D01*
G01Y268714D02*
X698859Y269130D01*
X699176Y269464D01*
X699619Y269630D01*
X700062Y269464D01*
X700379Y269130D01*
X700569Y268630D01*
Y266297D01*
G01X702819Y268547D02*
X704846D01*
X704656Y269130D01*
X704339Y269464D01*
X703896Y269630D01*
X703452Y269547D01*
X703072Y269297D01*
X702819Y268714D01*
X702692Y268214D01*
Y267714D01*
X702819Y267214D01*
X703136Y266714D01*
X703516Y266380D01*
X703959Y266297D01*
X704402Y266464D01*
X704846Y266964D01*
G01X708869Y271297D02*
Y266297D01*
G01X707982Y269630D02*
X709756D01*
G01X713019Y268547D02*
X715046D01*
X714856Y269130D01*
X714539Y269464D01*
X714096Y269630D01*
X713652Y269547D01*
X713272Y269297D01*
X713019Y268714D01*
X712892Y268214D01*
Y267714D01*
X713019Y267214D01*
X713336Y266714D01*
X713716Y266380D01*
X714159Y266297D01*
X714602Y266464D01*
X715046Y266964D01*
G01X718182Y266297D02*
Y269630D01*
G01Y268964D02*
X718499Y269297D01*
X718816Y269547D01*
X719259Y269630D01*
X719576Y269547D01*
X719956Y269297D01*
G01X727876Y267297D02*
X728256Y266714D01*
X728762Y266380D01*
X729332Y266297D01*
X729839Y266380D01*
X730346Y266797D01*
X730662Y267297D01*
X730726Y267797D01*
X730599Y268380D01*
X730156Y268797D01*
X729712Y268964D01*
X729142D01*
G01X729712D02*
X730092Y269214D01*
X730409Y269630D01*
X730536Y270130D01*
X730409Y270630D01*
X730092Y271047D01*
X729522Y271297D01*
X728952Y271214D01*
X728382Y270880D01*
G01X734369Y266130D02*
X734242Y266214D01*
Y266380D01*
X734369Y266464D01*
X734496Y266380D01*
Y266214D01*
X734369Y266130D01*
G01X739469Y266297D02*
Y271297D01*
X738709Y270297D01*
G01Y266297D02*
X740229D01*
G01X744442D02*
X744569Y267380D01*
X744759Y268297D01*
X745012Y269130D01*
X745329Y270047D01*
X745836Y271297D01*
X743302D01*
G01X748276Y267047D02*
X748656Y266630D01*
X749099Y266380D01*
X749669Y266297D01*
X750239Y266464D01*
X750682Y266797D01*
X750999Y267380D01*
X751062Y268047D01*
X750936Y268714D01*
X750619Y269130D01*
X750176Y269464D01*
X749732Y269547D01*
X749289Y269464D01*
X748719Y269130D01*
X748909Y271297D01*
X750619D01*
G01X752869Y266297D02*
Y269630D01*
G01Y268714D02*
X753059Y269130D01*
X753376Y269464D01*
X753819Y269630D01*
X754262Y269464D01*
X754579Y269130D01*
X754769Y268714D01*
Y266297D01*
G01Y268714D02*
X754959Y269130D01*
X755276Y269464D01*
X755719Y269630D01*
X756162Y269464D01*
X756479Y269130D01*
X756669Y268630D01*
Y266297D01*
G01X757969D02*
Y269630D01*
G01Y268714D02*
X758159Y269130D01*
X758476Y269464D01*
X758919Y269630D01*
X759362Y269464D01*
X759679Y269130D01*
X759869Y268714D01*
Y266297D01*
G01Y268714D02*
X760059Y269130D01*
X760376Y269464D01*
X760819Y269630D01*
X761262Y269464D01*
X761579Y269130D01*
X761769Y268630D01*
Y266297D01*
G01X768612D02*
Y271297D01*
X771526Y266297D01*
Y271297D01*
G01X773902Y266297D02*
Y271297D01*
X775422D01*
X775929Y271047D01*
X776309Y270464D01*
X776436Y269797D01*
X776309Y269130D01*
X775992Y268630D01*
X775422Y268380D01*
X773902D01*
G01X780269Y271297D02*
Y266297D01*
G01X778812Y271297D02*
X781726D01*
G01X784039Y266297D02*
Y271297D01*
G01X786699D02*
Y266297D01*
G01Y268797D02*
X784039D01*
G01X630725Y55645D02*
X630225Y56025D01*
X629975Y56468D01*
X629892Y56975D01*
X630059Y57608D01*
X630475Y58051D01*
X630975Y58178D01*
X631475Y58115D01*
X631892Y57861D01*
X632725Y56595D01*
X633309Y56025D01*
X634142Y55645D01*
X634892Y55518D01*
Y58178D01*
G01X638376Y47005D02*
X637392Y52911D01*
X636407Y47005D01*
X638376D01*
G01X636407Y66690D02*
X637392Y60785D01*
X638376Y66690D01*
X636407D01*
G01X637392Y56848D02*
Y60785D01*
G01Y56848D02*
Y52911D01*
G01X651959D02*
X636998D01*
G01X651959Y60785D02*
X636998D01*
G01X639222Y133525D02*
X652685Y111984D01*
G01X651811Y118100D02*
X656051Y120750D01*
X654800Y120864D01*
G01X651408Y118744D02*
X652214Y117455D01*
G01X643187Y129039D02*
X639222Y133525D01*
X641518Y127996D01*
X643187Y129039D01*
G01X655415Y124126D02*
X646405Y124391D01*
G01X653410Y124259D02*
G03I-2500J0D01*
G01X644771Y136080D02*
X675100Y143079D01*
G01X650304Y138367D02*
X644771Y136080D01*
X650747Y136449D01*
X650304Y138367D01*
G01X644517Y233867D02*
X688620Y243632D01*
G01X650071Y236105D02*
X644517Y233867D01*
X650496Y234183D01*
X650071Y236105D01*
G01X658170Y245852D02*
X654909Y237449D01*
G01X659039Y241650D02*
G03I-2500J0D01*
G01X671432Y38694D02*
X671812Y38111D01*
X672318Y37777D01*
X672888Y37694D01*
X673395Y37777D01*
X673902Y38194D01*
X674218Y38694D01*
X674282Y39194D01*
X674155Y39777D01*
X673712Y40194D01*
X673268Y40361D01*
X672698D01*
G01X673268D02*
X673648Y40611D01*
X673965Y41027D01*
X674092Y41527D01*
X673965Y42027D01*
X673648Y42444D01*
X673078Y42694D01*
X672508Y42611D01*
X671938Y42277D01*
G01X672825Y35194D02*
X678336D01*
G01X660620Y34210D02*
X666525Y35194D01*
X660620Y36179D01*
Y34210D01*
G01X672825Y35194D02*
X666525D01*
G01Y54486D02*
Y34801D01*
G01X667450Y144905D02*
X667951Y144422D01*
X668520Y144211D01*
X669094Y144258D01*
X669569Y144454D01*
X669969Y144973D01*
X670165Y145532D01*
X670114Y146033D01*
X669860Y146573D01*
X669334Y146879D01*
X668865Y146942D01*
X668309Y146814D01*
G01X668865Y146942D02*
X669179Y147271D01*
X669394Y147748D01*
X669405Y148264D01*
X669169Y148723D01*
X668767Y149058D01*
X668155Y149173D01*
X667618Y148964D01*
X667138Y148511D01*
G01X664509Y149614D02*
X661324Y141183D01*
G01X665417Y145398D02*
G03I-2501J0D01*
G01X661069Y241117D02*
X661566Y240629D01*
X662132Y240414D01*
X662707Y240455D01*
X663184Y240646D01*
X663588Y241163D01*
X663789Y241719D01*
X663743Y242221D01*
X663493Y242763D01*
X662970Y243074D01*
X662501Y243141D01*
X661945Y243018D01*
G01X662501Y243141D02*
X662818Y243467D01*
X663038Y243943D01*
X663053Y244458D01*
X662821Y244919D01*
X662422Y245257D01*
X661812Y245378D01*
X661273Y245174D01*
X660789Y244725D01*
G01X667660Y241381D02*
X667518Y241435D01*
X667482Y241598D01*
X667588Y241706D01*
X667730Y241652D01*
X667766Y241490D01*
X667660Y241381D01*
G01X672603Y242646D02*
X671522Y247527D01*
X670996Y246387D01*
G01X671861Y242481D02*
X673345Y242810D01*
G01X677458Y243720D02*
X677348Y244805D01*
X677335Y245741D01*
X677402Y246610D01*
X677514Y247573D01*
X677738Y248903D01*
X675265Y248356D01*
G01X681039Y245281D02*
X681500Y244956D01*
X681986Y244808D01*
X682561Y244850D01*
X683082Y245136D01*
X683442Y245557D01*
X683625Y246195D01*
X683543Y246859D01*
X683275Y247483D01*
X682876Y247821D01*
X682371Y248051D01*
X681920Y248036D01*
X681506Y247859D01*
X681021Y247411D01*
X680738Y249567D01*
X682408Y249937D01*
G01X684242Y36179D02*
X678336Y35194D01*
X684242Y34210D01*
Y36179D01*
G01X678336Y54486D02*
Y34801D01*
G01X786843Y-9294D02*
Y-4294D01*
X788363D01*
X788870Y-4544D01*
X789250Y-5127D01*
X789377Y-5794D01*
X789250Y-6461D01*
X788933Y-6961D01*
X788363Y-7211D01*
X786843D01*
G01X794350Y-9294D02*
Y-5961D01*
G01Y-6544D02*
X794097Y-6211D01*
X793717Y-6044D01*
X793273Y-5961D01*
X792830Y-6127D01*
X792450Y-6461D01*
X792197Y-6961D01*
X792070Y-7627D01*
X792197Y-8294D01*
X792450Y-8794D01*
X792830Y-9127D01*
X793273Y-9294D01*
X793717Y-9211D01*
X794097Y-8961D01*
X794350Y-8627D01*
G01X797233Y-9294D02*
Y-5961D01*
G01Y-6794D02*
X797487Y-6377D01*
X797867Y-6044D01*
X798373Y-5961D01*
X798817Y-6044D01*
X799197Y-6377D01*
X799387Y-6961D01*
Y-9294D01*
G01X802460Y-7044D02*
X804487D01*
X804297Y-6461D01*
X803980Y-6127D01*
X803537Y-5961D01*
X803093Y-6044D01*
X802713Y-6294D01*
X802460Y-6877D01*
X802333Y-7377D01*
Y-7877D01*
X802460Y-8377D01*
X802777Y-8877D01*
X803157Y-9211D01*
X803600Y-9294D01*
X804043Y-9127D01*
X804487Y-8627D01*
G01X808510Y-9294D02*
Y-4294D01*
G01X817443Y-9294D02*
Y-4294D01*
X819027D01*
X819533Y-4544D01*
X819850Y-4877D01*
X819977Y-5544D01*
X819850Y-6211D01*
X819470Y-6627D01*
X819027Y-6877D01*
X817443D01*
G01X819027D02*
X819977Y-9294D01*
G01X822860Y-7044D02*
X824887D01*
X824697Y-6461D01*
X824380Y-6127D01*
X823937Y-5961D01*
X823493Y-6044D01*
X823113Y-6294D01*
X822860Y-6877D01*
X822733Y-7377D01*
Y-7877D01*
X822860Y-8377D01*
X823177Y-8877D01*
X823557Y-9211D01*
X824000Y-9294D01*
X824443Y-9127D01*
X824887Y-8627D01*
G01X827770Y-5961D02*
X828910Y-9294D01*
X830050Y-5961D01*
G01X839617Y-6627D02*
X839870Y-6377D01*
X840060Y-5961D01*
X840187Y-5377D01*
X840060Y-4877D01*
X839807Y-4544D01*
X839363Y-4294D01*
X837653D01*
Y-9294D01*
X839743D01*
X840187Y-8961D01*
X840440Y-8461D01*
X840567Y-7877D01*
X840440Y-7294D01*
X840060Y-6794D01*
X839617Y-6627D01*
X837653D01*
G01X-247901Y-428634D02*
Y1008173D01*
X2091018D01*
Y-428634D01*
X-247901D01*
G01X-115095Y-307460D02*
X-115565Y-307145D01*
X-116113Y-306935D01*
X-116740D01*
X-117445Y-307250D01*
X-117993Y-307775D01*
X-118385Y-308405D01*
X-118698Y-309455D01*
X-118776Y-310400D01*
X-118620Y-311345D01*
X-118385Y-311975D01*
X-117915Y-312605D01*
X-117366Y-313025D01*
X-116818Y-313235D01*
X-116270D01*
X-115721Y-313025D01*
X-115251Y-312710D01*
X-114860Y-312290D01*
G01X-111458Y-306935D02*
X-109578D01*
G01X-110518D02*
Y-313235D01*
G01X-111458D02*
X-109578D01*
G01X-104218Y-306935D02*
Y-313235D01*
G01X-106020Y-306935D02*
X-102416D01*
G01X-97918Y-313235D02*
Y-310400D01*
X-99485Y-306935D01*
G01X-96351D02*
X-97918Y-310400D01*
G01X-87041Y-311975D02*
X-86571Y-312710D01*
X-85945Y-313130D01*
X-85240Y-313235D01*
X-84613Y-313130D01*
X-83986Y-312605D01*
X-83595Y-311975D01*
X-83516Y-311345D01*
X-83673Y-310610D01*
X-84221Y-310085D01*
X-84770Y-309875D01*
X-85475D01*
G01X-84770D02*
X-84300Y-309560D01*
X-83908Y-309035D01*
X-83751Y-308405D01*
X-83908Y-307775D01*
X-84300Y-307250D01*
X-85005Y-306935D01*
X-85710Y-307040D01*
X-86415Y-307460D01*
G01X-80741Y-311975D02*
X-80271Y-312710D01*
X-79645Y-313130D01*
X-78940Y-313235D01*
X-78313Y-313130D01*
X-77686Y-312605D01*
X-77295Y-311975D01*
X-77216Y-311345D01*
X-77373Y-310610D01*
X-77921Y-310085D01*
X-78470Y-309875D01*
X-79175D01*
G01X-78470D02*
X-78000Y-309560D01*
X-77608Y-309035D01*
X-77451Y-308405D01*
X-77608Y-307775D01*
X-78000Y-307250D01*
X-78705Y-306935D01*
X-79410Y-307040D01*
X-80115Y-307460D01*
G01X-74441Y-311975D02*
X-73971Y-312710D01*
X-73345Y-313130D01*
X-72640Y-313235D01*
X-72013Y-313130D01*
X-71386Y-312605D01*
X-70995Y-311975D01*
X-70916Y-311345D01*
X-71073Y-310610D01*
X-71621Y-310085D01*
X-72170Y-309875D01*
X-72875D01*
G01X-72170D02*
X-71700Y-309560D01*
X-71308Y-309035D01*
X-71151Y-308405D01*
X-71308Y-307775D01*
X-71700Y-307250D01*
X-72405Y-306935D01*
X-73110Y-307040D01*
X-73815Y-307460D01*
G01X-66575Y-313235D02*
X-66418Y-311870D01*
X-66183Y-310715D01*
X-65870Y-309665D01*
X-65478Y-308510D01*
X-64851Y-306935D01*
X-67985D01*
G01X-60275Y-313235D02*
X-60118Y-311870D01*
X-59883Y-310715D01*
X-59570Y-309665D01*
X-59178Y-308510D01*
X-58551Y-306935D01*
X-61685D01*
G01X-53975Y-314390D02*
X-53661Y-313025D01*
G01X-47518Y-306935D02*
Y-313235D01*
G01X-49320Y-306935D02*
X-45716D01*
G01X-43176Y-313235D02*
X-41218Y-306935D01*
X-39260Y-313235D01*
G01X-39965Y-311030D02*
X-42471D01*
G01X-35858Y-306935D02*
X-33978D01*
G01X-34918D02*
Y-313235D01*
G01X-35858D02*
X-33978D01*
G01X-30968Y-306935D02*
X-29871Y-313235D01*
X-28618Y-306935D01*
X-27365Y-313235D01*
X-26268Y-306935D01*
G01X-24276Y-313235D02*
X-22318Y-306935D01*
X-20360Y-313235D01*
G01X-21065Y-311030D02*
X-23571D01*
G01X-17820Y-313235D02*
Y-306935D01*
X-14216Y-313235D01*
Y-306935D01*
G01X-3810Y-315335D02*
X-4593Y-314285D01*
X-4985Y-313235D01*
Y-309035D01*
X-4593Y-307985D01*
X-3810Y-306935D01*
G01X7615Y-313235D02*
Y-306935D01*
X9574D01*
X10200Y-307250D01*
X10592Y-307670D01*
X10749Y-308510D01*
X10592Y-309350D01*
X10122Y-309875D01*
X9574Y-310190D01*
X7615D01*
G01X9574D02*
X10749Y-313235D01*
G01X15482Y-313445D02*
X15325Y-313340D01*
Y-313130D01*
X15482Y-313025D01*
X15639Y-313130D01*
Y-313340D01*
X15482Y-313445D01*
G01X21782Y-313235D02*
X21155Y-313130D01*
X20607Y-312710D01*
X20137Y-312080D01*
X19824Y-311345D01*
X19667Y-310505D01*
Y-309665D01*
X19824Y-308825D01*
X20137Y-308090D01*
X20607Y-307460D01*
X21155Y-307040D01*
X21782Y-306935D01*
X22409Y-307040D01*
X22957Y-307460D01*
X23427Y-308090D01*
X23740Y-308825D01*
X23897Y-309665D01*
Y-310505D01*
X23740Y-311345D01*
X23427Y-312080D01*
X22957Y-312710D01*
X22409Y-313130D01*
X21782Y-313235D01*
G01X28082Y-313445D02*
X27925Y-313340D01*
Y-313130D01*
X28082Y-313025D01*
X28239Y-313130D01*
Y-313340D01*
X28082Y-313445D01*
G01X36105Y-307460D02*
X35635Y-307145D01*
X35087Y-306935D01*
X34460D01*
X33755Y-307250D01*
X33207Y-307775D01*
X32815Y-308405D01*
X32502Y-309455D01*
X32424Y-310400D01*
X32580Y-311345D01*
X32815Y-311975D01*
X33285Y-312605D01*
X33834Y-313025D01*
X34382Y-313235D01*
X34930D01*
X35479Y-313025D01*
X35949Y-312710D01*
X36340Y-312290D01*
G01X40682Y-313445D02*
X40525Y-313340D01*
Y-313130D01*
X40682Y-313025D01*
X40839Y-313130D01*
Y-313340D01*
X40682Y-313445D01*
G01X47374Y-315335D02*
X48157Y-314285D01*
X48549Y-313235D01*
Y-309035D01*
X48157Y-307985D01*
X47374Y-306935D01*
G01X-118620Y-293235D02*
Y-286935D01*
X-115016Y-293235D01*
Y-286935D01*
G01X-110518Y-293235D02*
X-111145Y-293130D01*
X-111693Y-292710D01*
X-112163Y-292080D01*
X-112476Y-291345D01*
X-112633Y-290505D01*
Y-289665D01*
X-112476Y-288825D01*
X-112163Y-288090D01*
X-111693Y-287460D01*
X-111145Y-287040D01*
X-110518Y-286935D01*
X-109891Y-287040D01*
X-109343Y-287460D01*
X-108873Y-288090D01*
X-108560Y-288825D01*
X-108403Y-289665D01*
Y-290505D01*
X-108560Y-291345D01*
X-108873Y-292080D01*
X-109343Y-292710D01*
X-109891Y-293130D01*
X-110518Y-293235D01*
G01X-104218Y-293445D02*
X-104375Y-293340D01*
Y-293130D01*
X-104218Y-293025D01*
X-104061Y-293130D01*
Y-293340D01*
X-104218Y-293445D01*
G01X-99406Y-287985D02*
X-98936Y-287355D01*
X-98388Y-287040D01*
X-97761Y-286935D01*
X-96978Y-287145D01*
X-96430Y-287670D01*
X-96273Y-288300D01*
X-96351Y-288930D01*
X-96665Y-289455D01*
X-98231Y-290505D01*
X-98936Y-291240D01*
X-99406Y-292290D01*
X-99563Y-293235D01*
X-96273D01*
G01X-91618D02*
Y-286935D01*
X-92558Y-288195D01*
G01Y-293235D02*
X-90678D01*
G01X-85318D02*
Y-286935D01*
X-86258Y-288195D01*
G01Y-293235D02*
X-84378D01*
G01X-79175Y-294390D02*
X-78861Y-293025D01*
G01X-75068Y-286935D02*
X-73971Y-293235D01*
X-72718Y-286935D01*
X-71465Y-293235D01*
X-70368Y-286935D01*
G01X-64851Y-293235D02*
X-67985D01*
Y-286935D01*
X-64851D01*
G01X-66105Y-289980D02*
X-67985D01*
G01X-61920Y-293235D02*
Y-286935D01*
X-58316Y-293235D01*
Y-286935D01*
G01X-55463Y-293235D02*
Y-286935D01*
G01X-52173D02*
Y-293235D01*
G01Y-290085D02*
X-55463D01*
G01X-49241Y-286935D02*
Y-291450D01*
X-48928Y-292395D01*
X-48301Y-293025D01*
X-47518Y-293235D01*
X-46735Y-293025D01*
X-46108Y-292395D01*
X-45795Y-291450D01*
Y-286935D01*
G01X-43176Y-293235D02*
X-41218Y-286935D01*
X-39260Y-293235D01*
G01X-39965Y-291030D02*
X-42471D01*
G01X-30106Y-287985D02*
X-29636Y-287355D01*
X-29088Y-287040D01*
X-28461Y-286935D01*
X-27678Y-287145D01*
X-27130Y-287670D01*
X-26973Y-288300D01*
X-27051Y-288930D01*
X-27365Y-289455D01*
X-28931Y-290505D01*
X-29636Y-291240D01*
X-30106Y-292290D01*
X-30263Y-293235D01*
X-26973D01*
G01X-24120D02*
Y-286935D01*
X-20516Y-293235D01*
Y-286935D01*
G01X-17741Y-293235D02*
Y-286935D01*
X-16175D01*
X-15548Y-287250D01*
X-15078Y-287670D01*
X-14686Y-288300D01*
X-14373Y-289035D01*
X-14295Y-290085D01*
X-14373Y-291135D01*
X-14686Y-291870D01*
X-15078Y-292500D01*
X-15548Y-292920D01*
X-16175Y-293235D01*
X-17741D01*
G01X-4985D02*
Y-286935D01*
X-3026D01*
X-2400Y-287250D01*
X-2008Y-287670D01*
X-1851Y-288510D01*
X-2008Y-289350D01*
X-2478Y-289875D01*
X-3026Y-290190D01*
X-4985D01*
G01X-3026D02*
X-1851Y-293235D01*
G01X1159D02*
Y-286935D01*
X2725D01*
X3352Y-287250D01*
X3822Y-287670D01*
X4214Y-288300D01*
X4527Y-289035D01*
X4605Y-290085D01*
X4527Y-291135D01*
X4214Y-291870D01*
X3822Y-292500D01*
X3352Y-292920D01*
X2725Y-293235D01*
X1159D01*
G01X9182Y-293445D02*
X9025Y-293340D01*
Y-293130D01*
X9182Y-293025D01*
X9339Y-293130D01*
Y-293340D01*
X9182Y-293445D01*
G01X-116348Y-300085D02*
X-114781D01*
Y-301975D01*
X-115251Y-302605D01*
X-115800Y-303025D01*
X-116583Y-303235D01*
X-117366Y-303025D01*
X-117915Y-302605D01*
X-118385Y-301975D01*
X-118698Y-301240D01*
X-118855Y-300400D01*
Y-299665D01*
X-118698Y-299035D01*
X-118385Y-298300D01*
X-117915Y-297670D01*
X-117445Y-297250D01*
X-116818Y-296935D01*
X-116270D01*
X-115643Y-297145D01*
X-115173Y-297565D01*
G01X-112241Y-296935D02*
Y-301450D01*
X-111928Y-302395D01*
X-111301Y-303025D01*
X-110518Y-303235D01*
X-109735Y-303025D01*
X-109108Y-302395D01*
X-108795Y-301450D01*
Y-296935D01*
G01X-105158D02*
X-103278D01*
G01X-104218D02*
Y-303235D01*
G01X-105158D02*
X-103278D01*
G01X-99563Y-302395D02*
X-98936Y-302920D01*
X-98231Y-303235D01*
X-97605D01*
X-96978Y-302920D01*
X-96508Y-302395D01*
X-96273Y-301660D01*
X-96430Y-300925D01*
X-96821Y-300295D01*
X-97526Y-299875D01*
X-98466Y-299665D01*
X-99015Y-299245D01*
X-99250Y-298510D01*
X-99093Y-297775D01*
X-98701Y-297250D01*
X-98153Y-296935D01*
X-97605D01*
X-97056Y-297145D01*
X-96586Y-297670D01*
G01X-93263Y-303235D02*
Y-296935D01*
G01X-89973D02*
Y-303235D01*
G01Y-300085D02*
X-93263D01*
G01X-87276Y-303235D02*
X-85318Y-296935D01*
X-83360Y-303235D01*
G01X-84065Y-301030D02*
X-86571D01*
G01X-80820Y-303235D02*
Y-296935D01*
X-77216Y-303235D01*
Y-296935D01*
G01X-68141Y-303235D02*
Y-296935D01*
X-66575D01*
X-65948Y-297250D01*
X-65478Y-297670D01*
X-65086Y-298300D01*
X-64773Y-299035D01*
X-64695Y-300085D01*
X-64773Y-301135D01*
X-65086Y-301870D01*
X-65478Y-302500D01*
X-65948Y-302920D01*
X-66575Y-303235D01*
X-68141D01*
G01X-61058Y-296935D02*
X-59178D01*
G01X-60118D02*
Y-303235D01*
G01X-61058D02*
X-59178D01*
G01X-55463Y-302395D02*
X-54836Y-302920D01*
X-54131Y-303235D01*
X-53505D01*
X-52878Y-302920D01*
X-52408Y-302395D01*
X-52173Y-301660D01*
X-52330Y-300925D01*
X-52721Y-300295D01*
X-53426Y-299875D01*
X-54366Y-299665D01*
X-54915Y-299245D01*
X-55150Y-298510D01*
X-54993Y-297775D01*
X-54601Y-297250D01*
X-54053Y-296935D01*
X-53505D01*
X-52956Y-297145D01*
X-52486Y-297670D01*
G01X-47518Y-296935D02*
Y-303235D01*
G01X-49320Y-296935D02*
X-45716D01*
G01X-41218Y-303445D02*
X-41375Y-303340D01*
Y-303130D01*
X-41218Y-303025D01*
X-41061Y-303130D01*
Y-303340D01*
X-41218Y-303445D01*
G01X-35075Y-304390D02*
X-34761Y-303025D01*
G01X-28618Y-296935D02*
Y-303235D01*
G01X-30420Y-296935D02*
X-26816D01*
G01X-24276Y-303235D02*
X-22318Y-296935D01*
X-20360Y-303235D01*
G01X-21065Y-301030D02*
X-23571D01*
G01X-16018Y-303235D02*
X-16645Y-303130D01*
X-17193Y-302710D01*
X-17663Y-302080D01*
X-17976Y-301345D01*
X-18133Y-300505D01*
Y-299665D01*
X-17976Y-298825D01*
X-17663Y-298090D01*
X-17193Y-297460D01*
X-16645Y-297040D01*
X-16018Y-296935D01*
X-15391Y-297040D01*
X-14843Y-297460D01*
X-14373Y-298090D01*
X-14060Y-298825D01*
X-13903Y-299665D01*
Y-300505D01*
X-14060Y-301345D01*
X-14373Y-302080D01*
X-14843Y-302710D01*
X-15391Y-303130D01*
X-16018Y-303235D01*
G01X-9718D02*
Y-300400D01*
X-11285Y-296935D01*
G01X-8151D02*
X-9718Y-300400D01*
G01X-5141Y-296935D02*
Y-301450D01*
X-4828Y-302395D01*
X-4201Y-303025D01*
X-3418Y-303235D01*
X-2635Y-303025D01*
X-2008Y-302395D01*
X-1695Y-301450D01*
Y-296935D01*
G01X924Y-303235D02*
X2882Y-296935D01*
X4840Y-303235D01*
G01X4135Y-301030D02*
X1629D01*
G01X7380Y-303235D02*
Y-296935D01*
X10984Y-303235D01*
Y-296935D01*
G01X-94518Y-282535D02*
X-97038Y-282118D01*
X-99243Y-280452D01*
X-101133Y-277952D01*
X-102393Y-275035D01*
X-103023Y-271702D01*
Y-268368D01*
X-102393Y-265035D01*
X-101133Y-262118D01*
X-99243Y-259619D01*
X-97038Y-257952D01*
X-94518Y-257535D01*
X-91998Y-257952D01*
X-89793Y-259619D01*
X-87903Y-262118D01*
X-86643Y-265035D01*
X-86013Y-268368D01*
Y-271702D01*
X-86643Y-275035D01*
X-87903Y-277952D01*
X-89793Y-280452D01*
X-91998Y-282118D01*
X-94518Y-282535D01*
G01X-91998Y-275868D02*
X-88218Y-282535D01*
G01X-74673Y-265869D02*
Y-277535D01*
X-73413Y-280452D01*
X-71523Y-282118D01*
X-69318Y-282535D01*
X-67113Y-282118D01*
X-65223Y-280452D01*
X-63963Y-277535D01*
G01Y-282535D02*
Y-265869D01*
G01X-38448Y-282535D02*
Y-265869D01*
G01Y-268785D02*
X-39708Y-267119D01*
X-41598Y-266285D01*
X-43803Y-265869D01*
X-46008Y-266702D01*
X-47898Y-268368D01*
X-49158Y-270869D01*
X-49788Y-274202D01*
X-49158Y-277535D01*
X-47898Y-280036D01*
X-46008Y-281702D01*
X-43803Y-282535D01*
X-41598Y-282118D01*
X-39708Y-280869D01*
X-38448Y-279202D01*
G01X-24273Y-282535D02*
Y-265869D01*
G01Y-270035D02*
X-23013Y-267952D01*
X-21123Y-266285D01*
X-18603Y-265869D01*
X-16398Y-266285D01*
X-14508Y-267952D01*
X-13563Y-270869D01*
Y-282535D01*
G01X6282Y-257535D02*
Y-282535D01*
G01X1872Y-265869D02*
X10692D01*
G01X37152Y-282535D02*
Y-265869D01*
G01Y-268785D02*
X35892Y-267119D01*
X34002Y-266285D01*
X31797Y-265869D01*
X29592Y-266702D01*
X27702Y-268368D01*
X26442Y-270869D01*
X25812Y-274202D01*
X26442Y-277535D01*
X27702Y-280036D01*
X29592Y-281702D01*
X31797Y-282535D01*
X34002Y-282118D01*
X35892Y-280869D01*
X37152Y-279202D01*
G01X-51939Y19685D02*
G03I-6250J0D01*
G01X-52144Y121792D02*
Y126472D01*
G01Y124132D02*
X-36544D01*
G01Y121792D02*
Y126472D01*
G01X-38624Y137937D02*
X-37324Y139497D01*
X-36544Y141252D01*
Y142812D01*
X-37324Y144372D01*
X-38624Y145542D01*
X-40444Y146127D01*
X-42264Y145737D01*
X-43824Y144762D01*
X-44864Y143007D01*
X-45384Y140667D01*
X-46424Y139302D01*
X-48244Y138717D01*
X-50064Y139107D01*
X-51364Y140082D01*
X-52144Y141447D01*
Y142812D01*
X-51624Y144177D01*
X-50324Y145347D01*
G01X-52144Y159932D02*
X-36544D01*
G01X-52144Y155447D02*
Y164417D01*
G01X-44344Y196902D02*
Y200802D01*
X-39664D01*
X-38104Y199632D01*
X-37064Y198267D01*
X-36544Y196317D01*
X-37064Y194367D01*
X-38104Y193002D01*
X-39664Y191832D01*
X-41484Y191052D01*
X-43564Y190662D01*
X-45384D01*
X-46944Y191052D01*
X-48764Y191832D01*
X-50324Y193002D01*
X-51364Y194172D01*
X-52144Y195732D01*
Y197097D01*
X-51624Y198657D01*
X-50584Y199827D01*
G01X-36544Y217532D02*
Y209732D01*
X-52144D01*
Y217532D01*
G01X-44604Y214412D02*
Y209732D01*
G01X-36544Y227632D02*
X-52144D01*
Y232507D01*
X-51364Y234067D01*
X-50324Y235042D01*
X-48244Y235432D01*
X-46164Y235042D01*
X-44864Y233872D01*
X-44084Y232507D01*
Y227632D01*
G01Y232507D02*
X-36544Y235432D01*
G01X-44864Y250992D02*
X-45644Y251772D01*
X-46944Y252357D01*
X-48764Y252747D01*
X-50324Y252357D01*
X-51364Y251577D01*
X-52144Y250212D01*
Y244947D01*
X-36544D01*
Y251382D01*
X-37584Y252747D01*
X-39144Y253527D01*
X-40964Y253917D01*
X-42784Y253527D01*
X-44344Y252357D01*
X-44864Y250992D01*
Y244947D01*
G01X-36544Y271232D02*
Y263432D01*
X-52144D01*
Y271232D01*
G01X-44604Y268112D02*
Y263432D01*
G01X-36544Y281332D02*
X-52144D01*
Y286207D01*
X-51364Y287767D01*
X-50324Y288742D01*
X-48244Y289132D01*
X-46164Y288742D01*
X-44864Y287572D01*
X-44084Y286207D01*
Y281332D01*
G01Y286207D02*
X-36544Y289132D01*
G01X-31344Y302157D02*
X-33944Y300207D01*
X-36544Y299232D01*
X-46944D01*
X-49544Y300207D01*
X-52144Y302157D01*
G01Y321032D02*
X-36544D01*
G01X-52144Y316547D02*
Y325517D01*
G01Y334057D02*
X-36544Y338932D01*
X-52144Y343807D01*
G01X-36544Y352737D02*
X-52144Y360927D01*
G01Y352737D02*
X-36544Y360927D01*
G01X-52144Y374732D02*
X-51624Y373172D01*
X-50324Y372002D01*
X-48764Y371222D01*
X-46684Y370637D01*
X-44344Y370442D01*
X-42004Y370637D01*
X-39924Y371222D01*
X-38364Y372002D01*
X-37064Y373172D01*
X-36544Y374732D01*
X-37064Y376292D01*
X-38364Y377462D01*
X-39924Y378242D01*
X-42004Y378827D01*
X-44344Y379022D01*
X-46684Y378827D01*
X-48764Y378242D01*
X-50324Y377462D01*
X-51624Y376292D01*
X-52144Y374732D01*
G01X-36544Y394972D02*
X-52144D01*
X-40964Y387757D01*
Y397507D01*
G01X-49544Y406827D02*
X-51104Y407997D01*
X-51884Y409362D01*
X-52144Y410922D01*
X-51624Y412872D01*
X-50324Y414237D01*
X-48764Y414627D01*
X-47204Y414432D01*
X-45904Y413652D01*
X-43304Y409752D01*
X-41484Y407997D01*
X-38884Y406827D01*
X-36544Y406437D01*
Y414627D01*
G01X-49544Y424727D02*
X-51104Y425897D01*
X-51884Y427262D01*
X-52144Y428822D01*
X-51624Y430772D01*
X-50324Y432137D01*
X-48764Y432527D01*
X-47204Y432332D01*
X-45904Y431552D01*
X-43304Y427652D01*
X-41484Y425897D01*
X-38884Y424727D01*
X-36544Y424337D01*
Y432527D01*
G01X-52144Y446332D02*
X-51624Y444772D01*
X-50324Y443602D01*
X-48764Y442822D01*
X-46684Y442237D01*
X-44344Y442042D01*
X-42004Y442237D01*
X-39924Y442822D01*
X-38364Y443602D01*
X-37064Y444772D01*
X-36544Y446332D01*
X-37064Y447892D01*
X-38364Y449062D01*
X-39924Y449842D01*
X-42004Y450427D01*
X-44344Y450622D01*
X-46684Y450427D01*
X-48764Y449842D01*
X-50324Y449062D01*
X-51624Y447892D01*
X-52144Y446332D01*
G01X-36544Y459357D02*
X-52144Y464232D01*
X-36544Y469107D01*
G01X-42004Y467352D02*
Y461112D01*
G01X-31344Y483107D02*
X-33944Y485057D01*
X-36544Y486032D01*
X-46944D01*
X-49544Y485057D01*
X-52144Y483107D01*
G01X-52174Y544392D02*
X-52954Y543222D01*
X-53474Y541857D01*
Y540297D01*
X-52694Y538542D01*
X-51394Y537177D01*
X-49834Y536202D01*
X-47234Y535422D01*
X-44894Y535227D01*
X-42554Y535617D01*
X-40994Y536202D01*
X-39434Y537372D01*
X-38394Y538737D01*
X-37874Y540102D01*
Y541467D01*
X-38394Y542832D01*
X-39174Y544002D01*
X-40214Y544977D01*
G01X-46194Y559562D02*
X-46974Y560342D01*
X-48274Y560927D01*
X-50094Y561317D01*
X-51654Y560927D01*
X-52694Y560147D01*
X-53474Y558782D01*
Y553517D01*
X-37874D01*
Y559952D01*
X-38914Y561317D01*
X-40474Y562097D01*
X-42294Y562487D01*
X-44114Y562097D01*
X-45674Y560927D01*
X-46194Y559562D01*
Y553517D01*
G01X-52284Y638976D02*
G03I-5905J0D01*
G01X-51939Y666535D02*
G03I-6250J0D01*
G01X76832Y-262235D02*
Y-270235D01*
X80832D01*
G01X88632D02*
Y-264902D01*
G01Y-265835D02*
X88232Y-265302D01*
X87632Y-265035D01*
X86932Y-264902D01*
X86232Y-265168D01*
X85632Y-265702D01*
X85232Y-266502D01*
X85032Y-267568D01*
X85232Y-268635D01*
X85632Y-269435D01*
X86232Y-269968D01*
X86932Y-270235D01*
X87632Y-270102D01*
X88232Y-269702D01*
X88632Y-269169D01*
G01X92732Y-272635D02*
X93332Y-272902D01*
X94132Y-272635D01*
X94632Y-272102D01*
X95032Y-271435D01*
X95632Y-269302D01*
X96932Y-264902D01*
G01X93732D02*
X95632Y-269302D01*
G01X101332Y-266635D02*
X104532D01*
X104232Y-265702D01*
X103732Y-265168D01*
X103032Y-264902D01*
X102332Y-265035D01*
X101732Y-265435D01*
X101332Y-266368D01*
X101132Y-267169D01*
Y-267968D01*
X101332Y-268768D01*
X101832Y-269568D01*
X102432Y-270102D01*
X103132Y-270235D01*
X103832Y-269968D01*
X104532Y-269169D01*
G01X109432Y-270235D02*
Y-264902D01*
G01Y-265968D02*
X109932Y-265435D01*
X110432Y-265035D01*
X111132Y-264902D01*
X111632Y-265035D01*
X112232Y-265435D01*
G01X95532Y-320235D02*
Y-312235D01*
X100132Y-320235D01*
Y-312235D01*
G01X105832Y-314902D02*
Y-320235D01*
G01Y-312768D02*
X105632Y-312635D01*
Y-312368D01*
X105832Y-312235D01*
X106032Y-312368D01*
Y-312635D01*
X105832Y-312768D01*
G01X112132Y-320235D02*
Y-314902D01*
G01Y-316235D02*
X112532Y-315568D01*
X113132Y-315035D01*
X113932Y-314902D01*
X114632Y-315035D01*
X115232Y-315568D01*
X115532Y-316502D01*
Y-320235D01*
G01X123632D02*
Y-314902D01*
G01Y-315835D02*
X123232Y-315302D01*
X122632Y-315035D01*
X121932Y-314902D01*
X121232Y-315168D01*
X120632Y-315702D01*
X120232Y-316502D01*
X120032Y-317568D01*
X120232Y-318635D01*
X120632Y-319435D01*
X121232Y-319968D01*
X121932Y-320235D01*
X122632Y-320102D01*
X123232Y-319702D01*
X123632Y-319169D01*
G01X95832Y-295235D02*
Y-287235D01*
X98232D01*
X99032Y-287635D01*
X99632Y-288568D01*
X99832Y-289635D01*
X99632Y-290702D01*
X99132Y-291502D01*
X98232Y-291902D01*
X95832D01*
G01X103332Y-295235D02*
X105832Y-287235D01*
X108332Y-295235D01*
G01X107432Y-292435D02*
X104232D01*
G01X111532Y-295235D02*
Y-287235D01*
X116132Y-295235D01*
Y-287235D01*
G01X123832Y-295235D02*
X119832D01*
Y-287235D01*
X123832D01*
G01X122232Y-291102D02*
X119832D01*
G01X127832Y-287235D02*
Y-295235D01*
X131832D01*
G01X126126Y707470D02*
Y719970D01*
X124266Y717470D01*
G01Y707470D02*
X127986D01*
G01X138526D02*
Y719970D01*
X136666Y717470D01*
G01Y707470D02*
X140386D01*
G01X148291Y708928D02*
X149376Y707887D01*
X150616Y707470D01*
X151856Y707887D01*
X152941Y709136D01*
X153716Y711012D01*
X154026Y712887D01*
Y715178D01*
X153716Y717053D01*
X152941Y718720D01*
X152011Y719553D01*
X150926Y719970D01*
X149686Y719553D01*
X148756Y718720D01*
X148136Y717470D01*
X147826Y715803D01*
X148136Y714345D01*
X148911Y712887D01*
X149841Y712053D01*
X150926Y711845D01*
X152166Y712261D01*
X153096Y713303D01*
X154026Y715178D01*
G01X163326Y707053D02*
X163016Y707262D01*
Y707678D01*
X163326Y707887D01*
X163636Y707678D01*
Y707262D01*
X163326Y707053D01*
G01X172316Y709970D02*
X173246Y708511D01*
X174486Y707678D01*
X175881Y707470D01*
X177121Y707678D01*
X178361Y708720D01*
X179136Y709970D01*
X179291Y711220D01*
X178981Y712678D01*
X177896Y713720D01*
X176811Y714137D01*
X175416D01*
G01X176811D02*
X177741Y714762D01*
X178516Y715803D01*
X178826Y717053D01*
X178516Y718303D01*
X177741Y719345D01*
X176346Y719970D01*
X174951Y719762D01*
X173556Y718928D01*
G01X188126Y707470D02*
X189211Y707678D01*
X190451Y708303D01*
X191226Y709345D01*
X191536Y710803D01*
X191226Y712261D01*
X190296Y713512D01*
X188901Y714137D01*
X187351D01*
X186421Y714553D01*
X185646Y715595D01*
X185336Y717053D01*
X185801Y718512D01*
X186886Y719553D01*
X188126Y719970D01*
X189366Y719553D01*
X190451Y718512D01*
X190916Y717053D01*
X190606Y715595D01*
X189831Y714553D01*
X188901Y714137D01*
X187351D01*
X185956Y713512D01*
X185026Y712261D01*
X184716Y710803D01*
X185026Y709345D01*
X185801Y708303D01*
X187041Y707678D01*
X188126Y707470D01*
G01X121636Y732470D02*
Y744970D01*
X115901Y736012D01*
X123651D01*
G01X129231Y737678D02*
X130316Y739137D01*
X131246Y739970D01*
X132486Y740387D01*
X133571Y739970D01*
X134346Y739137D01*
X134966Y737887D01*
X135121Y736428D01*
X134966Y735178D01*
X134346Y733928D01*
X133416Y732887D01*
X132331Y732470D01*
X131091Y732887D01*
X130006Y734136D01*
X129386Y736012D01*
X129231Y738095D01*
X129541Y740803D01*
X130006Y742262D01*
X130781Y743720D01*
X131866Y744762D01*
X132951Y744970D01*
X134036Y744553D01*
X134811Y743512D01*
G01X141941Y733928D02*
X143026Y732887D01*
X144266Y732470D01*
X145506Y732887D01*
X146591Y734136D01*
X147366Y736012D01*
X147676Y737887D01*
Y740178D01*
X147366Y742053D01*
X146591Y743720D01*
X145661Y744553D01*
X144576Y744970D01*
X143336Y744553D01*
X142406Y743720D01*
X141786Y742470D01*
X141476Y740803D01*
X141786Y739345D01*
X142561Y737887D01*
X143491Y737053D01*
X144576Y736845D01*
X145816Y737261D01*
X146746Y738303D01*
X147676Y740178D01*
G01X154341Y733928D02*
X155426Y732887D01*
X156666Y732470D01*
X157906Y732887D01*
X158991Y734136D01*
X159766Y736012D01*
X160076Y737887D01*
Y740178D01*
X159766Y742053D01*
X158991Y743720D01*
X158061Y744553D01*
X156976Y744970D01*
X155736Y744553D01*
X154806Y743720D01*
X154186Y742470D01*
X153876Y740803D01*
X154186Y739345D01*
X154961Y737887D01*
X155891Y737053D01*
X156976Y736845D01*
X158216Y737261D01*
X159146Y738303D01*
X160076Y740178D01*
G01X169376Y732053D02*
X169066Y732262D01*
Y732678D01*
X169376Y732887D01*
X169686Y732678D01*
Y732262D01*
X169376Y732053D01*
G01X179141Y733928D02*
X180226Y732887D01*
X181466Y732470D01*
X182706Y732887D01*
X183791Y734136D01*
X184566Y736012D01*
X184876Y737887D01*
Y740178D01*
X184566Y742053D01*
X183791Y743720D01*
X182861Y744553D01*
X181776Y744970D01*
X180536Y744553D01*
X179606Y743720D01*
X178986Y742470D01*
X178676Y740803D01*
X178986Y739345D01*
X179761Y737887D01*
X180691Y737053D01*
X181776Y736845D01*
X183016Y737261D01*
X183946Y738303D01*
X184876Y740178D01*
G01X191541Y733928D02*
X192626Y732887D01*
X193866Y732470D01*
X195106Y732887D01*
X196191Y734136D01*
X196966Y736012D01*
X197276Y737887D01*
Y740178D01*
X196966Y742053D01*
X196191Y743720D01*
X195261Y744553D01*
X194176Y744970D01*
X192936Y744553D01*
X192006Y743720D01*
X191386Y742470D01*
X191076Y740803D01*
X191386Y739345D01*
X192161Y737887D01*
X193091Y737053D01*
X194176Y736845D01*
X195416Y737261D01*
X196346Y738303D01*
X197276Y740178D01*
G01X203432Y-313568D02*
X204032Y-312768D01*
X204732Y-312368D01*
X205532Y-312235D01*
X206532Y-312502D01*
X207232Y-313168D01*
X207432Y-313968D01*
X207332Y-314769D01*
X206932Y-315435D01*
X204932Y-316768D01*
X204032Y-317702D01*
X203432Y-319035D01*
X203232Y-320235D01*
X207432D01*
G01X213332Y-312235D02*
X212532Y-312502D01*
X211932Y-313168D01*
X211532Y-313968D01*
X211232Y-315035D01*
X211132Y-316235D01*
X211232Y-317435D01*
X211532Y-318502D01*
X211932Y-319302D01*
X212532Y-319968D01*
X213332Y-320235D01*
X214132Y-319968D01*
X214732Y-319302D01*
X215132Y-318502D01*
X215432Y-317435D01*
X215532Y-316235D01*
X215432Y-315035D01*
X215132Y-313968D01*
X214732Y-313168D01*
X214132Y-312502D01*
X213332Y-312235D01*
G01X219432Y-313568D02*
X220032Y-312768D01*
X220732Y-312368D01*
X221532Y-312235D01*
X222532Y-312502D01*
X223232Y-313168D01*
X223432Y-313968D01*
X223332Y-314769D01*
X222932Y-315435D01*
X220932Y-316768D01*
X220032Y-317702D01*
X219432Y-319035D01*
X219232Y-320235D01*
X223432D01*
G01X227432Y-313568D02*
X228032Y-312768D01*
X228732Y-312368D01*
X229532Y-312235D01*
X230532Y-312502D01*
X231232Y-313168D01*
X231432Y-313968D01*
X231332Y-314769D01*
X230932Y-315435D01*
X228932Y-316768D01*
X228032Y-317702D01*
X227432Y-319035D01*
X227232Y-320235D01*
X231432D01*
G01X235532Y-320502D02*
X239132Y-312235D01*
G01X245332Y-320235D02*
Y-312235D01*
X244132Y-313835D01*
G01Y-320235D02*
X246532D01*
G01X251432Y-313568D02*
X252032Y-312768D01*
X252732Y-312368D01*
X253532Y-312235D01*
X254532Y-312502D01*
X255232Y-313168D01*
X255432Y-313968D01*
X255332Y-314769D01*
X254932Y-315435D01*
X252932Y-316768D01*
X252032Y-317702D01*
X251432Y-319035D01*
X251232Y-320235D01*
X255432D01*
G01X259532Y-320502D02*
X263132Y-312235D01*
G01X269332D02*
X268532Y-312502D01*
X267932Y-313168D01*
X267532Y-313968D01*
X267232Y-315035D01*
X267132Y-316235D01*
X267232Y-317435D01*
X267532Y-318502D01*
X267932Y-319302D01*
X268532Y-319968D01*
X269332Y-320235D01*
X270132Y-319968D01*
X270732Y-319302D01*
X271132Y-318502D01*
X271432Y-317435D01*
X271532Y-316235D01*
X271432Y-315035D01*
X271132Y-313968D01*
X270732Y-313168D01*
X270132Y-312502D01*
X269332Y-312235D01*
G01X275632Y-319302D02*
X276332Y-319968D01*
X277132Y-320235D01*
X277932Y-319968D01*
X278632Y-319169D01*
X279132Y-317968D01*
X279332Y-316768D01*
Y-315302D01*
X279132Y-314102D01*
X278632Y-313035D01*
X278032Y-312502D01*
X277332Y-312235D01*
X276532Y-312502D01*
X275932Y-313035D01*
X275532Y-313835D01*
X275332Y-314902D01*
X275532Y-315835D01*
X276032Y-316768D01*
X276632Y-317302D01*
X277332Y-317435D01*
X278132Y-317169D01*
X278732Y-316502D01*
X279332Y-315302D01*
G01X205632Y-295235D02*
Y-287235D01*
X207632D01*
X208432Y-287635D01*
X209032Y-288168D01*
X209532Y-288968D01*
X209932Y-289902D01*
X210032Y-291235D01*
X209932Y-292568D01*
X209532Y-293502D01*
X209032Y-294302D01*
X208432Y-294835D01*
X207632Y-295235D01*
X205632D01*
G01X213332D02*
X215832Y-287235D01*
X218332Y-295235D01*
G01X217432Y-292435D02*
X214232D01*
G01X223832Y-287235D02*
X223032Y-287502D01*
X222432Y-288168D01*
X222032Y-288968D01*
X221732Y-290035D01*
X221632Y-291235D01*
X221732Y-292435D01*
X222032Y-293502D01*
X222432Y-294302D01*
X223032Y-294968D01*
X223832Y-295235D01*
X224632Y-294968D01*
X225232Y-294302D01*
X225632Y-293502D01*
X225932Y-292435D01*
X226032Y-291235D01*
X225932Y-290035D01*
X225632Y-288968D01*
X225232Y-288168D01*
X224632Y-287502D01*
X223832Y-287235D01*
G01X229932Y-295235D02*
Y-287235D01*
X233732D01*
G01X232332Y-291102D02*
X229932D01*
G01X239832Y-287235D02*
X239032Y-287502D01*
X238432Y-288168D01*
X238032Y-288968D01*
X237732Y-290035D01*
X237632Y-291235D01*
X237732Y-292435D01*
X238032Y-293502D01*
X238432Y-294302D01*
X239032Y-294968D01*
X239832Y-295235D01*
X240632Y-294968D01*
X241232Y-294302D01*
X241632Y-293502D01*
X241932Y-292435D01*
X242032Y-291235D01*
X241932Y-290035D01*
X241632Y-288968D01*
X241232Y-288168D01*
X240632Y-287502D01*
X239832Y-287235D01*
G01X247832D02*
Y-295235D01*
G01X245532Y-287235D02*
X250132D01*
G01X255832Y-295235D02*
Y-291635D01*
X253832Y-287235D01*
G01X257832D02*
X255832Y-291635D01*
G01X264632Y-290968D02*
X265032Y-290568D01*
X265332Y-289902D01*
X265532Y-288968D01*
X265332Y-288168D01*
X264932Y-287635D01*
X264232Y-287235D01*
X261532D01*
Y-295235D01*
X264832D01*
X265532Y-294702D01*
X265932Y-293902D01*
X266132Y-292968D01*
X265932Y-292035D01*
X265332Y-291235D01*
X264632Y-290968D01*
X261532D01*
G01X273032Y-295235D02*
Y-287235D01*
X269332Y-292968D01*
X274332D01*
G01X277632Y-295235D02*
Y-287235D01*
X279632D01*
X280432Y-287635D01*
X281032Y-288168D01*
X281532Y-288968D01*
X281932Y-289902D01*
X282032Y-291235D01*
X281932Y-292568D01*
X281532Y-293502D01*
X281032Y-294302D01*
X280432Y-294835D01*
X279632Y-295235D01*
X277632D01*
G01X287832Y-287235D02*
X287032Y-287502D01*
X286432Y-288168D01*
X286032Y-288968D01*
X285732Y-290035D01*
X285632Y-291235D01*
X285732Y-292435D01*
X286032Y-293502D01*
X286432Y-294302D01*
X287032Y-294968D01*
X287832Y-295235D01*
X288632Y-294968D01*
X289232Y-294302D01*
X289632Y-293502D01*
X289932Y-292435D01*
X290032Y-291235D01*
X289932Y-290035D01*
X289632Y-288968D01*
X289232Y-288168D01*
X288632Y-287502D01*
X287832Y-287235D01*
G01X233432Y-270235D02*
Y-262235D01*
X237232D01*
G01X235832Y-266102D02*
X233432D01*
G01X243332Y-262235D02*
X242532Y-262502D01*
X241932Y-263168D01*
X241532Y-263968D01*
X241232Y-265035D01*
X241132Y-266235D01*
X241232Y-267435D01*
X241532Y-268502D01*
X241932Y-269302D01*
X242532Y-269968D01*
X243332Y-270235D01*
X244132Y-269968D01*
X244732Y-269302D01*
X245132Y-268502D01*
X245432Y-267435D01*
X245532Y-266235D01*
X245432Y-265035D01*
X245132Y-263968D01*
X244732Y-263168D01*
X244132Y-262502D01*
X243332Y-262235D01*
G01X251332D02*
Y-270235D01*
G01X249032Y-262235D02*
X253632D01*
G01X256332Y-272902D02*
X262332D01*
G01X265332Y-270235D02*
Y-262235D01*
X267732D01*
X268532Y-262635D01*
X269132Y-263568D01*
X269332Y-264635D01*
X269132Y-265702D01*
X268632Y-266502D01*
X267732Y-266902D01*
X265332D01*
G01X272832Y-270235D02*
X275332Y-262235D01*
X277832Y-270235D01*
G01X276932Y-267435D02*
X273732D01*
G01X281032Y-270235D02*
Y-262235D01*
X285632Y-270235D01*
Y-262235D01*
G01X293332Y-270235D02*
X289332D01*
Y-262235D01*
X293332D01*
G01X291732Y-266102D02*
X289332D01*
G01X297332Y-262235D02*
Y-270235D01*
X301332D01*
G01X304332Y-272902D02*
X310332D01*
G01X316132Y-265968D02*
X316532Y-265568D01*
X316832Y-264902D01*
X317032Y-263968D01*
X316832Y-263168D01*
X316432Y-262635D01*
X315732Y-262235D01*
X313032D01*
Y-270235D01*
X316332D01*
X317032Y-269702D01*
X317432Y-268902D01*
X317632Y-267968D01*
X317432Y-267035D01*
X316832Y-266235D01*
X316132Y-265968D01*
X313032D01*
G01X321132Y-270235D02*
Y-262235D01*
X323132D01*
X323932Y-262635D01*
X324532Y-263168D01*
X325032Y-263968D01*
X325432Y-264902D01*
X325532Y-266235D01*
X325432Y-267568D01*
X325032Y-268502D01*
X324532Y-269302D01*
X323932Y-269835D01*
X323132Y-270235D01*
X321132D01*
G01X291832Y-323235D02*
Y-315235D01*
X290632Y-316835D01*
G01Y-323235D02*
X293032D01*
G01X297932Y-319902D02*
X298632Y-318968D01*
X299232Y-318435D01*
X300032Y-318168D01*
X300732Y-318435D01*
X301232Y-318968D01*
X301632Y-319768D01*
X301732Y-320702D01*
X301632Y-321502D01*
X301232Y-322302D01*
X300632Y-322968D01*
X299932Y-323235D01*
X299132Y-322968D01*
X298432Y-322169D01*
X298032Y-320968D01*
X297932Y-319635D01*
X298132Y-317902D01*
X298432Y-316968D01*
X298932Y-316035D01*
X299632Y-315368D01*
X300332Y-315235D01*
X301032Y-315502D01*
X301532Y-316168D01*
G01X307832Y-323502D02*
X307632Y-323368D01*
Y-323102D01*
X307832Y-322968D01*
X308032Y-323102D01*
Y-323368D01*
X307832Y-323502D01*
G01X313932Y-319902D02*
X314632Y-318968D01*
X315232Y-318435D01*
X316032Y-318168D01*
X316732Y-318435D01*
X317232Y-318968D01*
X317632Y-319768D01*
X317732Y-320702D01*
X317632Y-321502D01*
X317232Y-322302D01*
X316632Y-322968D01*
X315932Y-323235D01*
X315132Y-322968D01*
X314432Y-322169D01*
X314032Y-320968D01*
X313932Y-319635D01*
X314132Y-317902D01*
X314432Y-316968D01*
X314932Y-316035D01*
X315632Y-315368D01*
X316332Y-315235D01*
X317032Y-315502D01*
X317532Y-316168D01*
G01X336832Y-323235D02*
Y-315235D01*
X335632Y-316835D01*
G01Y-323235D02*
X338032D01*
G01X344632D02*
X344832Y-321502D01*
X345132Y-320035D01*
X345532Y-318702D01*
X346032Y-317235D01*
X346832Y-315235D01*
X342832D01*
G01X352832Y-323502D02*
X352632Y-323368D01*
Y-323102D01*
X352832Y-322968D01*
X353032Y-323102D01*
Y-323368D01*
X352832Y-323502D01*
G01X358932Y-316568D02*
X359532Y-315768D01*
X360232Y-315368D01*
X361032Y-315235D01*
X362032Y-315502D01*
X362732Y-316168D01*
X362932Y-316968D01*
X362832Y-317769D01*
X362432Y-318435D01*
X360432Y-319768D01*
X359532Y-320702D01*
X358932Y-322035D01*
X358732Y-323235D01*
X362932D01*
G01X356632Y-298235D02*
Y-290235D01*
X358632D01*
X359432Y-290635D01*
X360032Y-291168D01*
X360532Y-291968D01*
X360932Y-292902D01*
X361032Y-294235D01*
X360932Y-295568D01*
X360532Y-296502D01*
X360032Y-297302D01*
X359432Y-297835D01*
X358632Y-298235D01*
X356632D01*
G01X378690Y19685D02*
G03I-6250J0D01*
G01X378346Y66929D02*
G03I-5906J0D01*
G01X378690Y666535D02*
G03I-6250J0D01*
G01X420667Y302965D02*
X419208Y304050D01*
X418375Y304980D01*
X417958Y306220D01*
X418375Y307305D01*
X419208Y308080D01*
X420458Y308700D01*
X421917Y308855D01*
X423167Y308700D01*
X424417Y308080D01*
X425458Y307150D01*
X425875Y306065D01*
X425458Y304825D01*
X424209Y303740D01*
X422333Y303120D01*
X420250Y302965D01*
X417542Y303275D01*
X416083Y303740D01*
X414625Y304515D01*
X413583Y305600D01*
X413375Y306685D01*
X413792Y307770D01*
X414833Y308545D01*
G01X425875Y318310D02*
X425667Y319395D01*
X425042Y320635D01*
X424000Y321410D01*
X422542Y321720D01*
X421084Y321410D01*
X419833Y320480D01*
X419208Y319085D01*
Y317535D01*
X418792Y316605D01*
X417750Y315830D01*
X416292Y315520D01*
X414833Y315985D01*
X413792Y317070D01*
X413375Y318310D01*
X413792Y319550D01*
X414833Y320635D01*
X416292Y321100D01*
X417750Y320790D01*
X418792Y320015D01*
X419208Y319085D01*
Y317535D01*
X419833Y316140D01*
X421084Y315210D01*
X422542Y314900D01*
X424000Y315210D01*
X425042Y315985D01*
X425667Y317225D01*
X425875Y318310D01*
G01X420667Y327765D02*
X419208Y328850D01*
X418375Y329780D01*
X417958Y331020D01*
X418375Y332105D01*
X419208Y332880D01*
X420458Y333500D01*
X421917Y333655D01*
X423167Y333500D01*
X424417Y332880D01*
X425458Y331950D01*
X425875Y330865D01*
X425458Y329625D01*
X424209Y328540D01*
X422333Y327920D01*
X420250Y327765D01*
X417542Y328075D01*
X416083Y328540D01*
X414625Y329315D01*
X413583Y330400D01*
X413375Y331485D01*
X413792Y332570D01*
X414833Y333345D01*
G01X415458Y340165D02*
X414209Y341095D01*
X413583Y342180D01*
X413375Y343420D01*
X413792Y344970D01*
X414833Y346055D01*
X416083Y346365D01*
X417334Y346210D01*
X418375Y345590D01*
X420458Y342490D01*
X421917Y341095D01*
X424000Y340165D01*
X425875Y339855D01*
Y346365D01*
G01X426292Y355510D02*
X426083Y355200D01*
X425667D01*
X425458Y355510D01*
X425667Y355820D01*
X426083D01*
X426292Y355510D01*
G01X415458Y364965D02*
X414209Y365895D01*
X413583Y366980D01*
X413375Y368220D01*
X413792Y369770D01*
X414833Y370855D01*
X416083Y371165D01*
X417334Y371010D01*
X418375Y370390D01*
X420458Y367290D01*
X421917Y365895D01*
X424000Y364965D01*
X425875Y364655D01*
Y371165D01*
G01X413375Y380310D02*
X413792Y379070D01*
X414833Y378140D01*
X416083Y377520D01*
X417750Y377055D01*
X419625Y376900D01*
X421500Y377055D01*
X423167Y377520D01*
X424417Y378140D01*
X425458Y379070D01*
X425875Y380310D01*
X425458Y381550D01*
X424417Y382480D01*
X423167Y383100D01*
X421500Y383565D01*
X419625Y383720D01*
X417750Y383565D01*
X416083Y383100D01*
X414833Y382480D01*
X413792Y381550D01*
X413375Y380310D01*
G01X450875Y318460D02*
X438375D01*
X440875Y316600D01*
G01X450875D02*
Y320320D01*
G01Y330550D02*
X448167Y330860D01*
X445875Y331325D01*
X443792Y331945D01*
X441500Y332720D01*
X438375Y333960D01*
Y327760D01*
G01X450875Y345120D02*
X438375D01*
X447333Y339385D01*
Y347135D01*
G01X451292Y355660D02*
X451083Y355350D01*
X450667D01*
X450458Y355660D01*
X450667Y355970D01*
X451083D01*
X451292Y355660D01*
G01X448375Y364650D02*
X449834Y365580D01*
X450667Y366820D01*
X450875Y368215D01*
X450667Y369455D01*
X449625Y370695D01*
X448375Y371470D01*
X447125Y371625D01*
X445667Y371315D01*
X444625Y370230D01*
X444208Y369145D01*
Y367750D01*
G01Y369145D02*
X443583Y370075D01*
X442542Y370850D01*
X441292Y371160D01*
X440042Y370850D01*
X439000Y370075D01*
X438375Y368680D01*
X438583Y367285D01*
X439417Y365890D01*
G01X597628Y285438D02*
X842037D01*
Y1423D01*
X597628D01*
Y285438D01*
G01X644872Y134013D02*
G03I-5906J0D01*
G01X644665Y232516D02*
G03I-6250J0D01*
G01X653140Y60785D02*
X662588D01*
G02Y52911I0J-3937D01*
G01X653140D01*
G01X682273Y60785D02*
X691722D01*
G01X682273D02*
G03Y52911I0J-3937D01*
G01X691722D01*
M02*
